FILE_TYPE = MACRO_DRAWING;
SET COLOR_WIRE YELLOW;
SET COLOR_PROP ORANGE;
SET COLOR_DOT WHITE;
SET COLOR_ARC YELLOW;
SET COLOR_BODY GREEN;
SET COLOR_NOTE PURPLE;
SET PROP_DISPLAY VALUE;
SET PAGE_NUMBER P25;
FORCEADD GENOA_SP5..17
(-5025 5075);
FORCEPROP 1 LAST LOCATION U25
J 0
(-5620 6331);
DISPLAY 0.489362 (-5620 6331);
PAINT SKYBLUE (-5620 6331);
FORCEPROP 0 LAST $SEC 17
J 0
(-5600 6375);
DISPLAY 0.680851 (-5600 6375);
PAINT MONO (-5600 6375);
DISPLAY INVISIBLE (-5600 6375);
FORCEPROP 0 LAST CDS_SEC 17
J 0
(-5625 6250);
DISPLAY 1.021277 (-5625 6250);
DISPLAY INVISIBLE (-5625 6250);
FORCEPROP 0 LASTPIN (-5775 5825) $PN CM36
J 2
(-5785 5835);
DISPLAY 0.489362 (-5785 5835);
PAINT MONO (-5785 5835);
FORCEPROP 0 LASTPIN (-5775 5725) $PN CP36
J 2
(-5785 5735);
DISPLAY 0.489362 (-5785 5735);
PAINT MONO (-5785 5735);
FORCEPROP 0 LASTPIN (-5775 5625) $PN CT36
J 2
(-5785 5635);
DISPLAY 0.489362 (-5785 5635);
PAINT MONO (-5785 5635);
FORCEPROP 0 LASTPIN (-5775 5525) $PN CN33
J 2
(-5785 5535);
DISPLAY 0.489362 (-5785 5535);
PAINT MONO (-5785 5535);
FORCEPROP 0 LASTPIN (-5775 5425) $PN CU33
J 2
(-5785 5435);
DISPLAY 0.489362 (-5785 5435);
PAINT MONO (-5785 5435);
FORCEPROP 0 LASTPIN (-5775 5325) $PN CR33
J 2
(-5785 5335);
DISPLAY 0.489362 (-5785 5335);
PAINT MONO (-5785 5335);
FORCEPROP 0 LASTPIN (-5775 5225) $PN CN30
J 2
(-5785 5235);
DISPLAY 0.489362 (-5785 5235);
PAINT MONO (-5785 5235);
FORCEPROP 0 LASTPIN (-5775 5125) $PN CU30
J 2
(-5785 5135);
DISPLAY 0.489362 (-5785 5135);
PAINT MONO (-5785 5135);
FORCEPROP 0 LASTPIN (-5775 5025) $PN CR30
J 2
(-5785 5035);
DISPLAY 0.489362 (-5785 5035);
PAINT MONO (-5785 5035);
FORCEPROP 0 LASTPIN (-5775 4925) $PN CL27
J 2
(-5785 4935);
DISPLAY 0.489362 (-5785 4935);
PAINT MONO (-5785 4935);
FORCEPROP 0 LASTPIN (-5775 4825) $PN CU27
J 2
(-5785 4835);
DISPLAY 0.489362 (-5785 4835);
PAINT MONO (-5785 4835);
FORCEPROP 0 LASTPIN (-5775 4725) $PN CR27
J 2
(-5785 4735);
DISPLAY 0.489362 (-5785 4735);
PAINT MONO (-5785 4735);
FORCEPROP 0 LASTPIN (-5775 4625) $PN CN27
J 2
(-5785 4635);
DISPLAY 0.489362 (-5785 4635);
PAINT MONO (-5785 4635);
FORCEPROP 0 LASTPIN (-5775 4525) $PN CL24
J 2
(-5785 4535);
DISPLAY 0.489362 (-5785 4535);
PAINT MONO (-5785 4535);
FORCEPROP 0 LASTPIN (-5775 4425) $PN CR24
J 2
(-5785 4435);
DISPLAY 0.489362 (-5785 4435);
PAINT MONO (-5785 4435);
FORCEPROP 0 LASTPIN (-5775 4325) $PN CN24
J 2
(-5785 4335);
DISPLAY 0.489362 (-5785 4335);
PAINT MONO (-5785 4335);
FORCEPROP 0 LASTPIN (-5775 5875) $PN CM35
J 2
(-5785 5885);
DISPLAY 0.489362 (-5785 5885);
PAINT MONO (-5785 5885);
FORCEPROP 0 LASTPIN (-5775 5775) $PN CP35
J 2
(-5785 5785);
DISPLAY 0.489362 (-5785 5785);
PAINT MONO (-5785 5785);
FORCEPROP 0 LASTPIN (-5775 5675) $PN CT35
J 2
(-5785 5685);
DISPLAY 0.489362 (-5785 5685);
PAINT MONO (-5785 5685);
FORCEPROP 0 LASTPIN (-5775 5575) $PN CN32
J 2
(-5785 5585);
DISPLAY 0.489362 (-5785 5585);
PAINT MONO (-5785 5585);
FORCEPROP 0 LASTPIN (-5775 5475) $PN CU32
J 2
(-5785 5485);
DISPLAY 0.489362 (-5785 5485);
PAINT MONO (-5785 5485);
FORCEPROP 0 LASTPIN (-5775 5375) $PN CR32
J 2
(-5785 5385);
DISPLAY 0.489362 (-5785 5385);
PAINT MONO (-5785 5385);
FORCEPROP 0 LASTPIN (-5775 5275) $PN CN29
J 2
(-5785 5285);
DISPLAY 0.489362 (-5785 5285);
PAINT MONO (-5785 5285);
FORCEPROP 0 LASTPIN (-5775 5175) $PN CU29
J 2
(-5785 5185);
DISPLAY 0.489362 (-5785 5185);
PAINT MONO (-5785 5185);
FORCEPROP 0 LASTPIN (-5775 5075) $PN CR29
J 2
(-5785 5085);
DISPLAY 0.489362 (-5785 5085);
PAINT MONO (-5785 5085);
FORCEPROP 0 LASTPIN (-5775 4975) $PN CL26
J 2
(-5785 4985);
DISPLAY 0.489362 (-5785 4985);
PAINT MONO (-5785 4985);
FORCEPROP 0 LASTPIN (-5775 4875) $PN CU26
J 2
(-5785 4885);
DISPLAY 0.489362 (-5785 4885);
PAINT MONO (-5785 4885);
FORCEPROP 0 LASTPIN (-5775 4775) $PN CR26
J 2
(-5785 4785);
DISPLAY 0.489362 (-5785 4785);
PAINT MONO (-5785 4785);
FORCEPROP 0 LASTPIN (-5775 4675) $PN CN26
J 2
(-5785 4685);
DISPLAY 0.489362 (-5785 4685);
PAINT MONO (-5785 4685);
FORCEPROP 0 LASTPIN (-5775 4575) $PN CL23
J 2
(-5785 4585);
DISPLAY 0.489362 (-5785 4585);
PAINT MONO (-5785 4585);
FORCEPROP 0 LASTPIN (-5775 4475) $PN CR23
J 2
(-5785 4485);
DISPLAY 0.489362 (-5785 4485);
PAINT MONO (-5785 4485);
FORCEPROP 0 LASTPIN (-5775 4375) $PN CN23
J 2
(-5785 4385);
DISPLAY 0.489362 (-5785 4385);
PAINT MONO (-5785 4385);
FORCEPROP 0 LASTPIN (-4275 5825) $PN BT35
J 0
(-4265 5835);
DISPLAY 0.489362 (-4265 5835);
PAINT MONO (-4265 5835);
FORCEPROP 0 LASTPIN (-4275 5725) $PN BV35
J 0
(-4265 5735);
DISPLAY 0.489362 (-4265 5735);
PAINT MONO (-4265 5735);
FORCEPROP 0 LASTPIN (-4275 5625) $PN CB35
J 0
(-4265 5635);
DISPLAY 0.489362 (-4265 5635);
PAINT MONO (-4265 5635);
FORCEPROP 0 LASTPIN (-4275 5525) $PN BY35
J 0
(-4265 5535);
DISPLAY 0.489362 (-4265 5535);
PAINT MONO (-4265 5535);
FORCEPROP 0 LASTPIN (-4275 5425) $PN BU32
J 0
(-4265 5435);
DISPLAY 0.489362 (-4265 5435);
PAINT MONO (-4265 5435);
FORCEPROP 0 LASTPIN (-4275 5325) $PN CA32
J 0
(-4265 5335);
DISPLAY 0.489362 (-4265 5335);
PAINT MONO (-4265 5335);
FORCEPROP 0 LASTPIN (-4275 5225) $PN BW32
J 0
(-4265 5235);
DISPLAY 0.489362 (-4265 5235);
PAINT MONO (-4265 5235);
FORCEPROP 0 LASTPIN (-4275 5125) $PN BU29
J 0
(-4265 5135);
DISPLAY 0.489362 (-4265 5135);
PAINT MONO (-4265 5135);
FORCEPROP 0 LASTPIN (-4275 5025) $PN CA29
J 0
(-4265 5035);
DISPLAY 0.489362 (-4265 5035);
PAINT MONO (-4265 5035);
FORCEPROP 0 LASTPIN (-4275 4925) $PN BW29
J 0
(-4265 4935);
DISPLAY 0.489362 (-4265 4935);
PAINT MONO (-4265 4935);
FORCEPROP 0 LASTPIN (-4275 4825) $PN BU26
J 0
(-4265 4835);
DISPLAY 0.489362 (-4265 4835);
PAINT MONO (-4265 4835);
FORCEPROP 0 LASTPIN (-4275 4725) $PN CA26
J 0
(-4265 4735);
DISPLAY 0.489362 (-4265 4735);
PAINT MONO (-4265 4735);
FORCEPROP 0 LASTPIN (-4275 4625) $PN BW26
J 0
(-4265 4635);
DISPLAY 0.489362 (-4265 4635);
PAINT MONO (-4265 4635);
FORCEPROP 0 LASTPIN (-4275 4525) $PN BU23
J 0
(-4265 4535);
DISPLAY 0.489362 (-4265 4535);
PAINT MONO (-4265 4535);
FORCEPROP 0 LASTPIN (-4275 4425) $PN CA23
J 0
(-4265 4435);
DISPLAY 0.489362 (-4265 4435);
PAINT MONO (-4265 4435);
FORCEPROP 0 LASTPIN (-4275 4325) $PN BW23
J 0
(-4265 4335);
DISPLAY 0.489362 (-4265 4335);
PAINT MONO (-4265 4335);
FORCEPROP 0 LASTPIN (-4275 5875) $PN BT36
J 0
(-4265 5885);
DISPLAY 0.489362 (-4265 5885);
PAINT MONO (-4265 5885);
FORCEPROP 0 LASTPIN (-4275 5775) $PN BV36
J 0
(-4265 5785);
DISPLAY 0.489362 (-4265 5785);
PAINT MONO (-4265 5785);
FORCEPROP 0 LASTPIN (-4275 5675) $PN CB36
J 0
(-4265 5685);
DISPLAY 0.489362 (-4265 5685);
PAINT MONO (-4265 5685);
FORCEPROP 0 LASTPIN (-4275 5575) $PN BY36
J 0
(-4265 5585);
DISPLAY 0.489362 (-4265 5585);
PAINT MONO (-4265 5585);
FORCEPROP 0 LASTPIN (-4275 5475) $PN BU33
J 0
(-4265 5485);
DISPLAY 0.489362 (-4265 5485);
PAINT MONO (-4265 5485);
FORCEPROP 0 LASTPIN (-4275 5375) $PN CA33
J 0
(-4265 5385);
DISPLAY 0.489362 (-4265 5385);
PAINT MONO (-4265 5385);
FORCEPROP 0 LASTPIN (-4275 5275) $PN BW33
J 0
(-4265 5285);
DISPLAY 0.489362 (-4265 5285);
PAINT MONO (-4265 5285);
FORCEPROP 0 LASTPIN (-4275 5175) $PN BU30
J 0
(-4265 5185);
DISPLAY 0.489362 (-4265 5185);
PAINT MONO (-4265 5185);
FORCEPROP 0 LASTPIN (-4275 5075) $PN CA30
J 0
(-4265 5085);
DISPLAY 0.489362 (-4265 5085);
PAINT MONO (-4265 5085);
FORCEPROP 0 LASTPIN (-4275 4975) $PN BW30
J 0
(-4265 4985);
DISPLAY 0.489362 (-4265 4985);
PAINT MONO (-4265 4985);
FORCEPROP 0 LASTPIN (-4275 4875) $PN BU27
J 0
(-4265 4885);
DISPLAY 0.489362 (-4265 4885);
PAINT MONO (-4265 4885);
FORCEPROP 0 LASTPIN (-4275 4775) $PN CA27
J 0
(-4265 4785);
DISPLAY 0.489362 (-4265 4785);
PAINT MONO (-4265 4785);
FORCEPROP 0 LASTPIN (-4275 4675) $PN BW27
J 0
(-4265 4685);
DISPLAY 0.489362 (-4265 4685);
PAINT MONO (-4265 4685);
FORCEPROP 0 LASTPIN (-4275 4575) $PN BU24
J 0
(-4265 4585);
DISPLAY 0.489362 (-4265 4585);
PAINT MONO (-4265 4585);
FORCEPROP 0 LASTPIN (-4275 4475) $PN CA24
J 0
(-4265 4485);
DISPLAY 0.489362 (-4265 4485);
PAINT MONO (-4265 4485);
FORCEPROP 0 LASTPIN (-4275 4375) $PN BW24
J 0
(-4265 4385);
DISPLAY 0.489362 (-4265 4385);
PAINT MONO (-4265 4385);
FORCEPROP 2 LAST PART_TYPE SMLF
J 0
(-5625 6150);
DISPLAY 1.021277 (-5625 6150);
FORCEPROP 1 LAST MATERIAL IO
J 0
(-5620 6057);
DISPLAY 0.489362 (-5620 6057);
PAINT SKYBLUE (-5620 6057);
FORCEPROP 2 LAST VALUE SOCKET6096_13568-001
J 0
(-5625 6100);
DISPLAY 0.489362 (-5625 6100);
PAINT SKYBLUE (-5625 6100);
FORCEPROP 1 LAST PART_NUMBER DGA^6000030
J 0
(-5625 6250);
DISPLAY 0.489362 (-5625 6250);
PAINT SKYBLUE (-5625 6250);
FORCEPROP 2 LAST CDS_LIB pure_quanta
J 0
(-5025 5075);
DISPLAY INVISIBLE (-5025 5075);
FORCEPROP 1 LAST NEEDS_NO_SIZE TRUE
J 0
(-5025 5075);
DISPLAY 0.723404 (-5025 5075);
PAINT GREEN (-5025 5075);
DISPLAY INVISIBLE (-5025 5075);
FORCEPROP 1 LAST CDS_LMAN_SYM_OUTLINE -600,950,600,-950
J 0
(-5025 5075);
DISPLAY 0.468085 (-5025 5075);
PAINT GREEN (-5025 5075);
DISPLAY INVISIBLE (-5025 5075);
FORCEPROP 1 LAST PATH I147
J 0
(-5025 5075);
DISPLAY 0.723404 (-5025 5075);
PAINT GREEN (-5025 5075);
DISPLAY INVISIBLE (-5025 5075);
FORCEADD GENOA_SP5..18
(-5025 2250);
FORCEPROP 1 LAST LOCATION U25
J 0
(-5620 3506);
DISPLAY 0.489362 (-5620 3506);
PAINT SKYBLUE (-5620 3506);
FORCEPROP 0 LAST $SEC 18
J 0
(-5600 3550);
DISPLAY 0.680851 (-5600 3550);
PAINT MONO (-5600 3550);
DISPLAY INVISIBLE (-5600 3550);
FORCEPROP 0 LAST CDS_SEC 18
J 0
(-5625 3400);
DISPLAY 1.021277 (-5625 3400);
DISPLAY INVISIBLE (-5625 3400);
FORCEPROP 0 LASTPIN (-5775 3000) $PN CV36
J 2
(-5785 3010);
DISPLAY 0.489362 (-5785 3010);
PAINT MONO (-5785 3010);
FORCEPROP 0 LASTPIN (-5775 2900) $PN CY36
J 2
(-5785 2910);
DISPLAY 0.489362 (-5785 2910);
PAINT MONO (-5785 2910);
FORCEPROP 0 LASTPIN (-5775 2800) $PN DB36
J 2
(-5785 2810);
DISPLAY 0.489362 (-5785 2810);
PAINT MONO (-5785 2810);
FORCEPROP 0 LASTPIN (-5775 2700) $PN CW33
J 2
(-5785 2710);
DISPLAY 0.489362 (-5785 2710);
PAINT MONO (-5785 2710);
FORCEPROP 0 LASTPIN (-5775 2600) $PN DC33
J 2
(-5785 2610);
DISPLAY 0.489362 (-5785 2610);
PAINT MONO (-5785 2610);
FORCEPROP 0 LASTPIN (-5775 2500) $PN DA33
J 2
(-5785 2510);
DISPLAY 0.489362 (-5785 2510);
PAINT MONO (-5785 2510);
FORCEPROP 0 LASTPIN (-5775 2400) $PN CW30
J 2
(-5785 2410);
DISPLAY 0.489362 (-5785 2410);
PAINT MONO (-5785 2410);
FORCEPROP 0 LASTPIN (-5775 2300) $PN DC30
J 2
(-5785 2310);
DISPLAY 0.489362 (-5785 2310);
PAINT MONO (-5785 2310);
FORCEPROP 0 LASTPIN (-5775 2200) $PN DA30
J 2
(-5785 2210);
DISPLAY 0.489362 (-5785 2210);
PAINT MONO (-5785 2210);
FORCEPROP 0 LASTPIN (-5775 2100) $PN CW27
J 2
(-5785 2110);
DISPLAY 0.489362 (-5785 2110);
PAINT MONO (-5785 2110);
FORCEPROP 0 LASTPIN (-5775 2000) $PN DC27
J 2
(-5785 2010);
DISPLAY 0.489362 (-5785 2010);
PAINT MONO (-5785 2010);
FORCEPROP 0 LASTPIN (-5775 1900) $PN DA27
J 2
(-5785 1910);
DISPLAY 0.489362 (-5785 1910);
PAINT MONO (-5785 1910);
FORCEPROP 0 LASTPIN (-5775 1800) $PN CW24
J 2
(-5785 1810);
DISPLAY 0.489362 (-5785 1810);
PAINT MONO (-5785 1810);
FORCEPROP 0 LASTPIN (-5775 1700) $PN DC24
J 2
(-5785 1710);
DISPLAY 0.489362 (-5785 1710);
PAINT MONO (-5785 1710);
FORCEPROP 0 LASTPIN (-5775 1600) $PN DA24
J 2
(-5785 1610);
DISPLAY 0.489362 (-5785 1610);
PAINT MONO (-5785 1610);
FORCEPROP 0 LASTPIN (-5775 1500) $PN CU24
J 2
(-5785 1510);
DISPLAY 0.489362 (-5785 1510);
PAINT MONO (-5785 1510);
FORCEPROP 0 LASTPIN (-5775 3050) $PN CV35
J 2
(-5785 3060);
DISPLAY 0.489362 (-5785 3060);
PAINT MONO (-5785 3060);
FORCEPROP 0 LASTPIN (-5775 2950) $PN CY35
J 2
(-5785 2960);
DISPLAY 0.489362 (-5785 2960);
PAINT MONO (-5785 2960);
FORCEPROP 0 LASTPIN (-5775 2850) $PN DB35
J 2
(-5785 2860);
DISPLAY 0.489362 (-5785 2860);
PAINT MONO (-5785 2860);
FORCEPROP 0 LASTPIN (-5775 2750) $PN CW32
J 2
(-5785 2760);
DISPLAY 0.489362 (-5785 2760);
PAINT MONO (-5785 2760);
FORCEPROP 0 LASTPIN (-5775 2650) $PN DC32
J 2
(-5785 2660);
DISPLAY 0.489362 (-5785 2660);
PAINT MONO (-5785 2660);
FORCEPROP 0 LASTPIN (-5775 2550) $PN DA32
J 2
(-5785 2560);
DISPLAY 0.489362 (-5785 2560);
PAINT MONO (-5785 2560);
FORCEPROP 0 LASTPIN (-5775 2450) $PN CW29
J 2
(-5785 2460);
DISPLAY 0.489362 (-5785 2460);
PAINT MONO (-5785 2460);
FORCEPROP 0 LASTPIN (-5775 2350) $PN DC29
J 2
(-5785 2360);
DISPLAY 0.489362 (-5785 2360);
PAINT MONO (-5785 2360);
FORCEPROP 0 LASTPIN (-5775 2250) $PN DA29
J 2
(-5785 2260);
DISPLAY 0.489362 (-5785 2260);
PAINT MONO (-5785 2260);
FORCEPROP 0 LASTPIN (-5775 2150) $PN CW26
J 2
(-5785 2160);
DISPLAY 0.489362 (-5785 2160);
PAINT MONO (-5785 2160);
FORCEPROP 0 LASTPIN (-5775 2050) $PN DC26
J 2
(-5785 2060);
DISPLAY 0.489362 (-5785 2060);
PAINT MONO (-5785 2060);
FORCEPROP 0 LASTPIN (-5775 1950) $PN DA26
J 2
(-5785 1960);
DISPLAY 0.489362 (-5785 1960);
PAINT MONO (-5785 1960);
FORCEPROP 0 LASTPIN (-5775 1850) $PN CW23
J 2
(-5785 1860);
DISPLAY 0.489362 (-5785 1860);
PAINT MONO (-5785 1860);
FORCEPROP 0 LASTPIN (-5775 1750) $PN DC23
J 2
(-5785 1760);
DISPLAY 0.489362 (-5785 1760);
PAINT MONO (-5785 1760);
FORCEPROP 0 LASTPIN (-5775 1650) $PN DA23
J 2
(-5785 1660);
DISPLAY 0.489362 (-5785 1660);
PAINT MONO (-5785 1660);
FORCEPROP 0 LASTPIN (-5775 1550) $PN CU23
J 2
(-5785 1560);
DISPLAY 0.489362 (-5785 1560);
PAINT MONO (-5785 1560);
FORCEPROP 0 LASTPIN (-4275 3000) $PN CD35
J 0
(-4265 3010);
DISPLAY 0.489362 (-4265 3010);
PAINT MONO (-4265 3010);
FORCEPROP 0 LASTPIN (-4275 2900) $PN CF35
J 0
(-4265 2910);
DISPLAY 0.489362 (-4265 2910);
PAINT MONO (-4265 2910);
FORCEPROP 0 LASTPIN (-4275 2800) $PN CH35
J 0
(-4265 2810);
DISPLAY 0.489362 (-4265 2810);
PAINT MONO (-4265 2810);
FORCEPROP 0 LASTPIN (-4275 2700) $PN CC32
J 0
(-4265 2710);
DISPLAY 0.489362 (-4265 2710);
PAINT MONO (-4265 2710);
FORCEPROP 0 LASTPIN (-4275 2600) $PN CJ32
J 0
(-4265 2610);
DISPLAY 0.489362 (-4265 2610);
PAINT MONO (-4265 2610);
FORCEPROP 0 LASTPIN (-4275 2500) $PN CG32
J 0
(-4265 2510);
DISPLAY 0.489362 (-4265 2510);
PAINT MONO (-4265 2510);
FORCEPROP 0 LASTPIN (-4275 2400) $PN CE32
J 0
(-4265 2410);
DISPLAY 0.489362 (-4265 2410);
PAINT MONO (-4265 2410);
FORCEPROP 0 LASTPIN (-4275 2300) $PN CC29
J 0
(-4265 2310);
DISPLAY 0.489362 (-4265 2310);
PAINT MONO (-4265 2310);
FORCEPROP 0 LASTPIN (-4275 2200) $PN CG29
J 0
(-4265 2210);
DISPLAY 0.489362 (-4265 2210);
PAINT MONO (-4265 2210);
FORCEPROP 0 LASTPIN (-4275 2100) $PN CE29
J 0
(-4265 2110);
DISPLAY 0.489362 (-4265 2110);
PAINT MONO (-4265 2110);
FORCEPROP 0 LASTPIN (-4275 2000) $PN CC26
J 0
(-4265 2010);
DISPLAY 0.489362 (-4265 2010);
PAINT MONO (-4265 2010);
FORCEPROP 0 LASTPIN (-4275 1900) $PN CG26
J 0
(-4265 1910);
DISPLAY 0.489362 (-4265 1910);
PAINT MONO (-4265 1910);
FORCEPROP 0 LASTPIN (-4275 1800) $PN CE26
J 0
(-4265 1810);
DISPLAY 0.489362 (-4265 1810);
PAINT MONO (-4265 1810);
FORCEPROP 0 LASTPIN (-4275 1700) $PN CC23
J 0
(-4265 1710);
DISPLAY 0.489362 (-4265 1710);
PAINT MONO (-4265 1710);
FORCEPROP 0 LASTPIN (-4275 1600) $PN CG23
J 0
(-4265 1610);
DISPLAY 0.489362 (-4265 1610);
PAINT MONO (-4265 1610);
FORCEPROP 0 LASTPIN (-4275 1500) $PN CE23
J 0
(-4265 1510);
DISPLAY 0.489362 (-4265 1510);
PAINT MONO (-4265 1510);
FORCEPROP 0 LASTPIN (-4275 3050) $PN CD36
J 0
(-4265 3060);
DISPLAY 0.489362 (-4265 3060);
PAINT MONO (-4265 3060);
FORCEPROP 0 LASTPIN (-4275 2950) $PN CF36
J 0
(-4265 2960);
DISPLAY 0.489362 (-4265 2960);
PAINT MONO (-4265 2960);
FORCEPROP 0 LASTPIN (-4275 2850) $PN CH36
J 0
(-4265 2860);
DISPLAY 0.489362 (-4265 2860);
PAINT MONO (-4265 2860);
FORCEPROP 0 LASTPIN (-4275 2750) $PN CC33
J 0
(-4265 2760);
DISPLAY 0.489362 (-4265 2760);
PAINT MONO (-4265 2760);
FORCEPROP 0 LASTPIN (-4275 2650) $PN CJ33
J 0
(-4265 2660);
DISPLAY 0.489362 (-4265 2660);
PAINT MONO (-4265 2660);
FORCEPROP 0 LASTPIN (-4275 2550) $PN CG33
J 0
(-4265 2560);
DISPLAY 0.489362 (-4265 2560);
PAINT MONO (-4265 2560);
FORCEPROP 0 LASTPIN (-4275 2450) $PN CE33
J 0
(-4265 2460);
DISPLAY 0.489362 (-4265 2460);
PAINT MONO (-4265 2460);
FORCEPROP 0 LASTPIN (-4275 2350) $PN CC30
J 0
(-4265 2360);
DISPLAY 0.489362 (-4265 2360);
PAINT MONO (-4265 2360);
FORCEPROP 0 LASTPIN (-4275 2250) $PN CG30
J 0
(-4265 2260);
DISPLAY 0.489362 (-4265 2260);
PAINT MONO (-4265 2260);
FORCEPROP 0 LASTPIN (-4275 2150) $PN CE30
J 0
(-4265 2160);
DISPLAY 0.489362 (-4265 2160);
PAINT MONO (-4265 2160);
FORCEPROP 0 LASTPIN (-4275 2050) $PN CC27
J 0
(-4265 2060);
DISPLAY 0.489362 (-4265 2060);
PAINT MONO (-4265 2060);
FORCEPROP 0 LASTPIN (-4275 1950) $PN CG27
J 0
(-4265 1960);
DISPLAY 0.489362 (-4265 1960);
PAINT MONO (-4265 1960);
FORCEPROP 0 LASTPIN (-4275 1850) $PN CE27
J 0
(-4265 1860);
DISPLAY 0.489362 (-4265 1860);
PAINT MONO (-4265 1860);
FORCEPROP 0 LASTPIN (-4275 1750) $PN CC24
J 0
(-4265 1760);
DISPLAY 0.489362 (-4265 1760);
PAINT MONO (-4265 1760);
FORCEPROP 0 LASTPIN (-4275 1650) $PN CG24
J 0
(-4265 1660);
DISPLAY 0.489362 (-4265 1660);
PAINT MONO (-4265 1660);
FORCEPROP 0 LASTPIN (-4275 1550) $PN CE24
J 0
(-4265 1560);
DISPLAY 0.489362 (-4265 1560);
PAINT MONO (-4265 1560);
FORCEPROP 2 LAST PART_TYPE SMLF
J 0
(-5625 3350);
DISPLAY 1.021277 (-5625 3350);
FORCEPROP 1 LAST MATERIAL IO
J 0
(-5620 3232);
DISPLAY 0.489362 (-5620 3232);
PAINT SKYBLUE (-5620 3232);
FORCEPROP 2 LAST VALUE SOCKET6096_13568-001
J 0
(-5625 3250);
DISPLAY 0.489362 (-5625 3250);
PAINT SKYBLUE (-5625 3250);
FORCEPROP 1 LAST PART_NUMBER DGA^6000030
J 0
(-5620 3359);
DISPLAY 0.489362 (-5620 3359);
PAINT SKYBLUE (-5620 3359);
FORCEPROP 1 LAST CDS_LMAN_SYM_OUTLINE -600,950,600,-950
J 0
(-5025 2250);
DISPLAY 0.468085 (-5025 2250);
PAINT GREEN (-5025 2250);
DISPLAY INVISIBLE (-5025 2250);
FORCEPROP 1 LAST NEEDS_NO_SIZE TRUE
J 0
(-5025 2250);
DISPLAY 0.723404 (-5025 2250);
PAINT GREEN (-5025 2250);
DISPLAY INVISIBLE (-5025 2250);
FORCEPROP 2 LAST CDS_LIB pure_quanta
J 0
(-5025 2250);
DISPLAY INVISIBLE (-5025 2250);
FORCEPROP 1 LAST PATH I148
J 0
(-5025 2250);
DISPLAY 0.723404 (-5025 2250);
PAINT GREEN (-5025 2250);
DISPLAY INVISIBLE (-5025 2250);
FORCEADD OFFPAGE..2
(-2725 6100);
FORCEPROP 2 LAST $XR0 64 
J 0
(-2536 6100);
DISPLAY 0.638298 (-2536 6100);
PAINT MONO (-2536 6100);
FORCEPROP 2 LAST PATH I149
J 0
(-2525 6150);
DISPLAY 1.021277 (-2525 6150);
DISPLAY INVISIBLE (-2525 6150);
FORCEPROP 1 LAST COMMENT_BODY TRUE
J 0
(-2770 6005);
DISPLAY 0.872340 (-2770 6005);
PAINT GREEN (-2770 6005);
DISPLAY INVISIBLE (-2770 6005);
FORCEPROP 1 LAST OFFPAGE TRUE
J 0
(-2400 5975);
DISPLAY 0.872340 (-2400 5975);
PAINT GREEN (-2400 5975);
DISPLAY INVISIBLE (-2400 5975);
FORCEPROP 2 LAST CDS_LIB standard
J 0
(-2725 6100);
DISPLAY INVISIBLE (-2725 6100);
FORCEADD OFFPAGE..2
(-2725 6050);
FORCEPROP 2 LAST $XR0 64 
J 0
(-2536 6050);
DISPLAY 0.638298 (-2536 6050);
PAINT MONO (-2536 6050);
FORCEPROP 2 LAST PATH I150
J 0
(-2525 6100);
DISPLAY 1.021277 (-2525 6100);
DISPLAY INVISIBLE (-2525 6100);
FORCEPROP 1 LAST COMMENT_BODY TRUE
J 0
(-2770 5955);
DISPLAY 0.872340 (-2770 5955);
PAINT GREEN (-2770 5955);
DISPLAY INVISIBLE (-2770 5955);
FORCEPROP 1 LAST OFFPAGE TRUE
J 0
(-2400 5925);
DISPLAY 0.872340 (-2400 5925);
PAINT GREEN (-2400 5925);
DISPLAY INVISIBLE (-2400 5925);
FORCEPROP 2 LAST CDS_LIB standard
J 0
(-2725 6050);
DISPLAY INVISIBLE (-2725 6050);
FORCEADD TAP..6
R 2
(-3700 5725);
FORCEPROP 3 LASTPIN (-3750 5725) SIG_NAME P5E_CPU0_P2_TX_DN<1>
J 0
(-3740 5735);
DISPLAY 0.659574 (-3740 5735);
PAINT MONO (-3740 5735);
DISPLAY INVISIBLE (-3740 5735);
FORCEPROP 1 LASTPIN (-3750 5725) BN 1
J 2
(-3698 5733);
DISPLAY 0.489362 (-3698 5733);
PAINT MONO (-3698 5733);
FORCEPROP 2 LAST CDS_LIB mstr_standard
J 0
(-3700 5725);
DISPLAY INVISIBLE (-3700 5725);
FORCEPROP 2 LAST BOM_COST IO_SLOT
J 0
(-4200 5825);
DISPLAY 0.829787 (-4200 5825);
DISPLAY INVISIBLE (-4200 5825);
FORCEPROP 1 LAST BODY_TYPE PLUMBING
J 2
(-3700 5675);
DISPLAY 0.702128 (-3700 5675);
PAINT GREEN (-3700 5675);
DISPLAY INVISIBLE (-3700 5675);
FORCEPROP 1 LAST HDL_TAP TRUE
J 2
(-4025 5600);
DISPLAY 0.702128 (-4025 5600);
PAINT GREEN (-4025 5600);
DISPLAY INVISIBLE (-4025 5600);
FORCEPROP 1 LAST PATH I151
J 2
(-3698 5725);
DISPLAY 0.872340 (-3698 5725);
PAINT GREEN (-3698 5725);
DISPLAY INVISIBLE (-3698 5725);
FORCEPROP 2 LAST ROOM RISER1
J 0
(-4200 5775);
DISPLAY 0.829787 (-4200 5775);
PAINT RED (-4200 5775);
DISPLAY INVISIBLE (-4200 5775);
FORCEADD TAP..6
R 2
(-3700 5825);
FORCEPROP 3 LASTPIN (-3750 5825) SIG_NAME P5E_CPU0_P2_TX_DN<0>
J 0
(-3740 5835);
DISPLAY 0.659574 (-3740 5835);
PAINT MONO (-3740 5835);
DISPLAY INVISIBLE (-3740 5835);
FORCEPROP 1 LASTPIN (-3750 5825) BN 0
J 2
(-3698 5833);
DISPLAY 0.489362 (-3698 5833);
PAINT MONO (-3698 5833);
FORCEPROP 2 LAST BOM_COST IO_SLOT
J 0
(-4200 5925);
DISPLAY 0.829787 (-4200 5925);
DISPLAY INVISIBLE (-4200 5925);
FORCEPROP 2 LAST CDS_LIB mstr_standard
J 0
(-3700 5825);
DISPLAY INVISIBLE (-3700 5825);
FORCEPROP 1 LAST BODY_TYPE PLUMBING
J 2
(-3700 5775);
DISPLAY 0.702128 (-3700 5775);
PAINT GREEN (-3700 5775);
DISPLAY INVISIBLE (-3700 5775);
FORCEPROP 1 LAST HDL_TAP TRUE
J 2
(-4025 5700);
DISPLAY 0.702128 (-4025 5700);
PAINT GREEN (-4025 5700);
DISPLAY INVISIBLE (-4025 5700);
FORCEPROP 1 LAST PATH I152
J 2
(-3698 5825);
DISPLAY 0.872340 (-3698 5825);
PAINT GREEN (-3698 5825);
DISPLAY INVISIBLE (-3698 5825);
FORCEPROP 2 LAST ROOM RISER1
J 0
(-4200 5875);
DISPLAY 0.829787 (-4200 5875);
PAINT RED (-4200 5875);
DISPLAY INVISIBLE (-4200 5875);
FORCEADD TAP..6
R 2
(-3850 5875);
FORCEPROP 3 LASTPIN (-3900 5875) SIG_NAME P5E_CPU0_P2_TX_DP<0>
J 0
(-3890 5885);
DISPLAY 0.659574 (-3890 5885);
PAINT MONO (-3890 5885);
DISPLAY INVISIBLE (-3890 5885);
FORCEPROP 1 LASTPIN (-3900 5875) BN 0
J 2
(-3848 5883);
DISPLAY 0.489362 (-3848 5883);
PAINT MONO (-3848 5883);
FORCEPROP 2 LAST CDS_LIB mstr_standard
J 0
(-3850 5875);
DISPLAY INVISIBLE (-3850 5875);
FORCEPROP 2 LAST BOM_COST IO_SLOT
J 0
(-4350 5975);
DISPLAY 0.829787 (-4350 5975);
DISPLAY INVISIBLE (-4350 5975);
FORCEPROP 1 LAST BODY_TYPE PLUMBING
J 2
(-3850 5825);
DISPLAY 0.702128 (-3850 5825);
PAINT GREEN (-3850 5825);
DISPLAY INVISIBLE (-3850 5825);
FORCEPROP 1 LAST HDL_TAP TRUE
J 2
(-4175 5750);
DISPLAY 0.702128 (-4175 5750);
PAINT GREEN (-4175 5750);
DISPLAY INVISIBLE (-4175 5750);
FORCEPROP 1 LAST PATH I153
J 2
(-3848 5875);
DISPLAY 0.872340 (-3848 5875);
PAINT GREEN (-3848 5875);
DISPLAY INVISIBLE (-3848 5875);
FORCEPROP 2 LAST ROOM RISER1
J 0
(-4350 5925);
DISPLAY 0.829787 (-4350 5925);
PAINT RED (-4350 5925);
DISPLAY INVISIBLE (-4350 5925);
FORCEADD TAP..6
R 2
(-3850 5775);
FORCEPROP 3 LASTPIN (-3900 5775) SIG_NAME P5E_CPU0_P2_TX_DP<1>
J 0
(-3890 5785);
DISPLAY 0.659574 (-3890 5785);
PAINT MONO (-3890 5785);
DISPLAY INVISIBLE (-3890 5785);
FORCEPROP 1 LASTPIN (-3900 5775) BN 1
J 2
(-3848 5783);
DISPLAY 0.489362 (-3848 5783);
PAINT MONO (-3848 5783);
FORCEPROP 2 LAST CDS_LIB mstr_standard
J 0
(-3850 5775);
DISPLAY INVISIBLE (-3850 5775);
FORCEPROP 2 LAST BOM_COST IO_SLOT
J 0
(-4350 5875);
DISPLAY 0.829787 (-4350 5875);
DISPLAY INVISIBLE (-4350 5875);
FORCEPROP 1 LAST BODY_TYPE PLUMBING
J 2
(-3850 5725);
DISPLAY 0.702128 (-3850 5725);
PAINT GREEN (-3850 5725);
DISPLAY INVISIBLE (-3850 5725);
FORCEPROP 1 LAST HDL_TAP TRUE
J 2
(-4175 5650);
DISPLAY 0.702128 (-4175 5650);
PAINT GREEN (-4175 5650);
DISPLAY INVISIBLE (-4175 5650);
FORCEPROP 1 LAST PATH I154
J 2
(-3848 5775);
DISPLAY 0.872340 (-3848 5775);
PAINT GREEN (-3848 5775);
DISPLAY INVISIBLE (-3848 5775);
FORCEPROP 2 LAST ROOM RISER1
J 0
(-4350 5825);
DISPLAY 0.829787 (-4350 5825);
PAINT RED (-4350 5825);
DISPLAY INVISIBLE (-4350 5825);
FORCEADD TAP..6
R 2
(-3700 5625);
FORCEPROP 3 LASTPIN (-3750 5625) SIG_NAME P5E_CPU0_P2_TX_DN<2>
J 0
(-3740 5635);
DISPLAY 0.659574 (-3740 5635);
PAINT MONO (-3740 5635);
DISPLAY INVISIBLE (-3740 5635);
FORCEPROP 1 LASTPIN (-3750 5625) BN 2
J 2
(-3698 5633);
DISPLAY 0.489362 (-3698 5633);
PAINT MONO (-3698 5633);
FORCEPROP 2 LAST CDS_LIB standard
J 0
(-3700 5625);
DISPLAY INVISIBLE (-3700 5625);
FORCEPROP 2 LAST BOM_COST IO_SLOT
J 0
(-4200 5725);
DISPLAY 0.829787 (-4200 5725);
DISPLAY INVISIBLE (-4200 5725);
FORCEPROP 1 LAST BODY_TYPE PLUMBING
J 2
(-3700 5575);
DISPLAY 0.702128 (-3700 5575);
PAINT GREEN (-3700 5575);
DISPLAY INVISIBLE (-3700 5575);
FORCEPROP 1 LAST HDL_TAP TRUE
J 2
(-4025 5500);
DISPLAY 0.702128 (-4025 5500);
PAINT GREEN (-4025 5500);
DISPLAY INVISIBLE (-4025 5500);
FORCEPROP 1 LAST PATH I155
J 2
(-3698 5625);
DISPLAY 0.872340 (-3698 5625);
PAINT GREEN (-3698 5625);
DISPLAY INVISIBLE (-3698 5625);
FORCEPROP 2 LAST ROOM RISER1
J 0
(-4200 5675);
DISPLAY 0.829787 (-4200 5675);
PAINT RED (-4200 5675);
DISPLAY INVISIBLE (-4200 5675);
FORCEADD TAP..6
R 2
(-3700 5525);
FORCEPROP 3 LASTPIN (-3750 5525) SIG_NAME P5E_CPU0_P2_TX_DN<3>
J 0
(-3740 5535);
DISPLAY 0.659574 (-3740 5535);
PAINT MONO (-3740 5535);
DISPLAY INVISIBLE (-3740 5535);
FORCEPROP 1 LASTPIN (-3750 5525) BN 3
J 2
(-3698 5533);
DISPLAY 0.489362 (-3698 5533);
PAINT MONO (-3698 5533);
FORCEPROP 2 LAST CDS_LIB standard
J 0
(-3700 5525);
DISPLAY INVISIBLE (-3700 5525);
FORCEPROP 2 LAST BOM_COST IO_SLOT
J 0
(-4200 5625);
DISPLAY 0.829787 (-4200 5625);
DISPLAY INVISIBLE (-4200 5625);
FORCEPROP 1 LAST BODY_TYPE PLUMBING
J 2
(-3700 5475);
DISPLAY 0.702128 (-3700 5475);
PAINT GREEN (-3700 5475);
DISPLAY INVISIBLE (-3700 5475);
FORCEPROP 1 LAST HDL_TAP TRUE
J 2
(-4025 5400);
DISPLAY 0.702128 (-4025 5400);
PAINT GREEN (-4025 5400);
DISPLAY INVISIBLE (-4025 5400);
FORCEPROP 1 LAST PATH I156
J 2
(-3698 5525);
DISPLAY 0.872340 (-3698 5525);
PAINT GREEN (-3698 5525);
DISPLAY INVISIBLE (-3698 5525);
FORCEPROP 2 LAST ROOM RISER1
J 0
(-4200 5575);
DISPLAY 0.829787 (-4200 5575);
PAINT RED (-4200 5575);
DISPLAY INVISIBLE (-4200 5575);
FORCEADD TAP..6
R 2
(-3850 5675);
FORCEPROP 3 LASTPIN (-3900 5675) SIG_NAME P5E_CPU0_P2_TX_DP<2>
J 0
(-3890 5685);
DISPLAY 0.659574 (-3890 5685);
PAINT MONO (-3890 5685);
DISPLAY INVISIBLE (-3890 5685);
FORCEPROP 1 LASTPIN (-3900 5675) BN 2
J 2
(-3848 5683);
DISPLAY 0.489362 (-3848 5683);
PAINT MONO (-3848 5683);
FORCEPROP 2 LAST CDS_LIB standard
J 0
(-3850 5675);
DISPLAY INVISIBLE (-3850 5675);
FORCEPROP 2 LAST BOM_COST IO_SLOT
J 0
(-4350 5775);
DISPLAY 0.829787 (-4350 5775);
DISPLAY INVISIBLE (-4350 5775);
FORCEPROP 1 LAST BODY_TYPE PLUMBING
J 2
(-3850 5625);
DISPLAY 0.702128 (-3850 5625);
PAINT GREEN (-3850 5625);
DISPLAY INVISIBLE (-3850 5625);
FORCEPROP 1 LAST HDL_TAP TRUE
J 2
(-4175 5550);
DISPLAY 0.702128 (-4175 5550);
PAINT GREEN (-4175 5550);
DISPLAY INVISIBLE (-4175 5550);
FORCEPROP 1 LAST PATH I157
J 2
(-3848 5675);
DISPLAY 0.872340 (-3848 5675);
PAINT GREEN (-3848 5675);
DISPLAY INVISIBLE (-3848 5675);
FORCEPROP 2 LAST ROOM RISER1
J 0
(-4350 5725);
DISPLAY 0.829787 (-4350 5725);
PAINT RED (-4350 5725);
DISPLAY INVISIBLE (-4350 5725);
FORCEADD TAP..6
R 2
(-3850 5575);
FORCEPROP 3 LASTPIN (-3900 5575) SIG_NAME P5E_CPU0_P2_TX_DP<3>
J 0
(-3890 5585);
DISPLAY 0.659574 (-3890 5585);
PAINT MONO (-3890 5585);
DISPLAY INVISIBLE (-3890 5585);
FORCEPROP 1 LASTPIN (-3900 5575) BN 3
J 2
(-3848 5583);
DISPLAY 0.489362 (-3848 5583);
PAINT MONO (-3848 5583);
FORCEPROP 2 LAST CDS_LIB standard
J 0
(-3850 5575);
DISPLAY INVISIBLE (-3850 5575);
FORCEPROP 2 LAST BOM_COST IO_SLOT
J 0
(-4350 5675);
DISPLAY 0.829787 (-4350 5675);
DISPLAY INVISIBLE (-4350 5675);
FORCEPROP 1 LAST BODY_TYPE PLUMBING
J 2
(-3850 5525);
DISPLAY 0.702128 (-3850 5525);
PAINT GREEN (-3850 5525);
DISPLAY INVISIBLE (-3850 5525);
FORCEPROP 1 LAST HDL_TAP TRUE
J 2
(-4175 5450);
DISPLAY 0.702128 (-4175 5450);
PAINT GREEN (-4175 5450);
DISPLAY INVISIBLE (-4175 5450);
FORCEPROP 1 LAST PATH I158
J 2
(-3848 5575);
DISPLAY 0.872340 (-3848 5575);
PAINT GREEN (-3848 5575);
DISPLAY INVISIBLE (-3848 5575);
FORCEPROP 2 LAST ROOM RISER1
J 0
(-4350 5625);
DISPLAY 0.829787 (-4350 5625);
PAINT RED (-4350 5625);
DISPLAY INVISIBLE (-4350 5625);
FORCEADD TAP..6
R 2
(-3850 5475);
FORCEPROP 3 LASTPIN (-3900 5475) SIG_NAME P5E_CPU0_P2_TX_DP<4>
J 0
(-3890 5485);
DISPLAY 0.659574 (-3890 5485);
PAINT MONO (-3890 5485);
DISPLAY INVISIBLE (-3890 5485);
FORCEPROP 1 LASTPIN (-3900 5475) BN 4
J 2
(-3848 5483);
DISPLAY 0.489362 (-3848 5483);
PAINT MONO (-3848 5483);
FORCEPROP 2 LAST CDS_LIB standard
J 0
(-3850 5475);
DISPLAY INVISIBLE (-3850 5475);
FORCEPROP 2 LAST BOM_COST IO_SLOT
J 0
(-4350 5575);
DISPLAY 0.829787 (-4350 5575);
DISPLAY INVISIBLE (-4350 5575);
FORCEPROP 1 LAST BODY_TYPE PLUMBING
J 2
(-3850 5425);
DISPLAY 0.702128 (-3850 5425);
PAINT GREEN (-3850 5425);
DISPLAY INVISIBLE (-3850 5425);
FORCEPROP 1 LAST HDL_TAP TRUE
J 2
(-4175 5350);
DISPLAY 0.702128 (-4175 5350);
PAINT GREEN (-4175 5350);
DISPLAY INVISIBLE (-4175 5350);
FORCEPROP 1 LAST PATH I159
J 2
(-3848 5475);
DISPLAY 0.872340 (-3848 5475);
PAINT GREEN (-3848 5475);
DISPLAY INVISIBLE (-3848 5475);
FORCEPROP 2 LAST ROOM RISER1
J 0
(-4350 5525);
DISPLAY 0.829787 (-4350 5525);
PAINT RED (-4350 5525);
DISPLAY INVISIBLE (-4350 5525);
FORCEADD TAP..6
R 2
(-3700 5325);
FORCEPROP 3 LASTPIN (-3750 5325) SIG_NAME P5E_CPU0_P2_TX_DN<5>
J 0
(-3740 5335);
DISPLAY 0.659574 (-3740 5335);
PAINT MONO (-3740 5335);
DISPLAY INVISIBLE (-3740 5335);
FORCEPROP 1 LASTPIN (-3750 5325) BN 5
J 2
(-3698 5333);
DISPLAY 0.489362 (-3698 5333);
PAINT MONO (-3698 5333);
FORCEPROP 2 LAST CDS_LIB standard
J 0
(-3700 5325);
DISPLAY INVISIBLE (-3700 5325);
FORCEPROP 2 LAST BOM_COST IO_SLOT
J 0
(-4200 5425);
DISPLAY 0.829787 (-4200 5425);
DISPLAY INVISIBLE (-4200 5425);
FORCEPROP 1 LAST BODY_TYPE PLUMBING
J 2
(-3700 5275);
DISPLAY 0.702128 (-3700 5275);
PAINT GREEN (-3700 5275);
DISPLAY INVISIBLE (-3700 5275);
FORCEPROP 1 LAST HDL_TAP TRUE
J 2
(-4025 5200);
DISPLAY 0.702128 (-4025 5200);
PAINT GREEN (-4025 5200);
DISPLAY INVISIBLE (-4025 5200);
FORCEPROP 1 LAST PATH I160
J 2
(-3698 5325);
DISPLAY 0.872340 (-3698 5325);
PAINT GREEN (-3698 5325);
DISPLAY INVISIBLE (-3698 5325);
FORCEPROP 2 LAST ROOM RISER1
J 0
(-4200 5375);
DISPLAY 0.829787 (-4200 5375);
PAINT RED (-4200 5375);
DISPLAY INVISIBLE (-4200 5375);
FORCEADD TAP..6
R 2
(-3700 5425);
FORCEPROP 3 LASTPIN (-3750 5425) SIG_NAME P5E_CPU0_P2_TX_DN<4>
J 0
(-3740 5435);
DISPLAY 0.659574 (-3740 5435);
PAINT MONO (-3740 5435);
DISPLAY INVISIBLE (-3740 5435);
FORCEPROP 1 LASTPIN (-3750 5425) BN 4
J 2
(-3698 5433);
DISPLAY 0.489362 (-3698 5433);
PAINT MONO (-3698 5433);
FORCEPROP 2 LAST CDS_LIB standard
J 0
(-3700 5425);
DISPLAY INVISIBLE (-3700 5425);
FORCEPROP 2 LAST BOM_COST IO_SLOT
J 0
(-4200 5525);
DISPLAY 0.829787 (-4200 5525);
DISPLAY INVISIBLE (-4200 5525);
FORCEPROP 1 LAST BODY_TYPE PLUMBING
J 2
(-3700 5375);
DISPLAY 0.702128 (-3700 5375);
PAINT GREEN (-3700 5375);
DISPLAY INVISIBLE (-3700 5375);
FORCEPROP 1 LAST HDL_TAP TRUE
J 2
(-4025 5300);
DISPLAY 0.702128 (-4025 5300);
PAINT GREEN (-4025 5300);
DISPLAY INVISIBLE (-4025 5300);
FORCEPROP 1 LAST PATH I161
J 2
(-3698 5425);
DISPLAY 0.872340 (-3698 5425);
PAINT GREEN (-3698 5425);
DISPLAY INVISIBLE (-3698 5425);
FORCEPROP 2 LAST ROOM RISER1
J 0
(-4200 5475);
DISPLAY 0.829787 (-4200 5475);
PAINT RED (-4200 5475);
DISPLAY INVISIBLE (-4200 5475);
FORCEADD TAP..6
R 2
(-3700 5225);
FORCEPROP 3 LASTPIN (-3750 5225) SIG_NAME P5E_CPU0_P2_TX_DN<6>
J 0
(-3740 5235);
DISPLAY 0.659574 (-3740 5235);
PAINT MONO (-3740 5235);
DISPLAY INVISIBLE (-3740 5235);
FORCEPROP 1 LASTPIN (-3750 5225) BN 6
J 2
(-3698 5233);
DISPLAY 0.489362 (-3698 5233);
PAINT MONO (-3698 5233);
FORCEPROP 2 LAST CDS_LIB standard
J 0
(-3700 5225);
DISPLAY INVISIBLE (-3700 5225);
FORCEPROP 2 LAST BOM_COST IO_SLOT
J 0
(-4200 5325);
DISPLAY 0.829787 (-4200 5325);
DISPLAY INVISIBLE (-4200 5325);
FORCEPROP 1 LAST BODY_TYPE PLUMBING
J 2
(-3700 5175);
DISPLAY 0.702128 (-3700 5175);
PAINT GREEN (-3700 5175);
DISPLAY INVISIBLE (-3700 5175);
FORCEPROP 1 LAST HDL_TAP TRUE
J 2
(-4025 5100);
DISPLAY 0.702128 (-4025 5100);
PAINT GREEN (-4025 5100);
DISPLAY INVISIBLE (-4025 5100);
FORCEPROP 1 LAST PATH I162
J 2
(-3698 5225);
DISPLAY 0.872340 (-3698 5225);
PAINT GREEN (-3698 5225);
DISPLAY INVISIBLE (-3698 5225);
FORCEPROP 2 LAST ROOM RISER1
J 0
(-4200 5275);
DISPLAY 0.829787 (-4200 5275);
PAINT RED (-4200 5275);
DISPLAY INVISIBLE (-4200 5275);
FORCEADD TAP..6
R 2
(-3850 5375);
FORCEPROP 3 LASTPIN (-3900 5375) SIG_NAME P5E_CPU0_P2_TX_DP<5>
J 0
(-3890 5385);
DISPLAY 0.659574 (-3890 5385);
PAINT MONO (-3890 5385);
DISPLAY INVISIBLE (-3890 5385);
FORCEPROP 1 LASTPIN (-3900 5375) BN 5
J 2
(-3848 5383);
DISPLAY 0.489362 (-3848 5383);
PAINT MONO (-3848 5383);
FORCEPROP 2 LAST CDS_LIB standard
J 0
(-3850 5375);
DISPLAY INVISIBLE (-3850 5375);
FORCEPROP 2 LAST BOM_COST IO_SLOT
J 0
(-4350 5475);
DISPLAY 0.829787 (-4350 5475);
DISPLAY INVISIBLE (-4350 5475);
FORCEPROP 1 LAST BODY_TYPE PLUMBING
J 2
(-3850 5325);
DISPLAY 0.702128 (-3850 5325);
PAINT GREEN (-3850 5325);
DISPLAY INVISIBLE (-3850 5325);
FORCEPROP 1 LAST HDL_TAP TRUE
J 2
(-4175 5250);
DISPLAY 0.702128 (-4175 5250);
PAINT GREEN (-4175 5250);
DISPLAY INVISIBLE (-4175 5250);
FORCEPROP 1 LAST PATH I163
J 2
(-3848 5375);
DISPLAY 0.872340 (-3848 5375);
PAINT GREEN (-3848 5375);
DISPLAY INVISIBLE (-3848 5375);
FORCEPROP 2 LAST ROOM RISER1
J 0
(-4350 5425);
DISPLAY 0.829787 (-4350 5425);
PAINT RED (-4350 5425);
DISPLAY INVISIBLE (-4350 5425);
FORCEADD TAP..6
R 2
(-3850 5275);
FORCEPROP 3 LASTPIN (-3900 5275) SIG_NAME P5E_CPU0_P2_TX_DP<6>
J 0
(-3890 5285);
DISPLAY 0.659574 (-3890 5285);
PAINT MONO (-3890 5285);
DISPLAY INVISIBLE (-3890 5285);
FORCEPROP 1 LASTPIN (-3900 5275) BN 6
J 2
(-3848 5283);
DISPLAY 0.489362 (-3848 5283);
PAINT MONO (-3848 5283);
FORCEPROP 2 LAST CDS_LIB standard
J 0
(-3850 5275);
DISPLAY INVISIBLE (-3850 5275);
FORCEPROP 2 LAST BOM_COST IO_SLOT
J 0
(-4350 5375);
DISPLAY 0.829787 (-4350 5375);
DISPLAY INVISIBLE (-4350 5375);
FORCEPROP 1 LAST BODY_TYPE PLUMBING
J 2
(-3850 5225);
DISPLAY 0.702128 (-3850 5225);
PAINT GREEN (-3850 5225);
DISPLAY INVISIBLE (-3850 5225);
FORCEPROP 1 LAST HDL_TAP TRUE
J 2
(-4175 5150);
DISPLAY 0.702128 (-4175 5150);
PAINT GREEN (-4175 5150);
DISPLAY INVISIBLE (-4175 5150);
FORCEPROP 1 LAST PATH I164
J 2
(-3848 5275);
DISPLAY 0.872340 (-3848 5275);
PAINT GREEN (-3848 5275);
DISPLAY INVISIBLE (-3848 5275);
FORCEPROP 2 LAST ROOM RISER1
J 0
(-4350 5325);
DISPLAY 0.829787 (-4350 5325);
PAINT RED (-4350 5325);
DISPLAY INVISIBLE (-4350 5325);
FORCEADD TAP..6
R 2
(-3700 5125);
FORCEPROP 3 LASTPIN (-3750 5125) SIG_NAME P5E_CPU0_P2_TX_DN<7>
J 0
(-3740 5135);
DISPLAY 0.659574 (-3740 5135);
PAINT MONO (-3740 5135);
DISPLAY INVISIBLE (-3740 5135);
FORCEPROP 1 LASTPIN (-3750 5125) BN 7
J 2
(-3698 5133);
DISPLAY 0.489362 (-3698 5133);
PAINT MONO (-3698 5133);
FORCEPROP 2 LAST CDS_LIB standard
J 0
(-3700 5125);
DISPLAY INVISIBLE (-3700 5125);
FORCEPROP 2 LAST BOM_COST IO_SLOT
J 0
(-4200 5225);
DISPLAY 0.829787 (-4200 5225);
DISPLAY INVISIBLE (-4200 5225);
FORCEPROP 1 LAST BODY_TYPE PLUMBING
J 2
(-3700 5075);
DISPLAY 0.702128 (-3700 5075);
PAINT GREEN (-3700 5075);
DISPLAY INVISIBLE (-3700 5075);
FORCEPROP 1 LAST HDL_TAP TRUE
J 2
(-4025 5000);
DISPLAY 0.702128 (-4025 5000);
PAINT GREEN (-4025 5000);
DISPLAY INVISIBLE (-4025 5000);
FORCEPROP 1 LAST PATH I165
J 2
(-3698 5125);
DISPLAY 0.872340 (-3698 5125);
PAINT GREEN (-3698 5125);
DISPLAY INVISIBLE (-3698 5125);
FORCEPROP 2 LAST ROOM RISER1
J 0
(-4200 5175);
DISPLAY 0.829787 (-4200 5175);
PAINT RED (-4200 5175);
DISPLAY INVISIBLE (-4200 5175);
FORCEADD TAP..6
R 2
(-3700 5025);
FORCEPROP 3 LASTPIN (-3750 5025) SIG_NAME P5E_CPU0_P2_TX_DN<8>
J 0
(-3740 5035);
DISPLAY 0.659574 (-3740 5035);
PAINT MONO (-3740 5035);
DISPLAY INVISIBLE (-3740 5035);
FORCEPROP 1 LASTPIN (-3750 5025) BN 8
J 2
(-3698 5033);
DISPLAY 0.489362 (-3698 5033);
PAINT MONO (-3698 5033);
FORCEPROP 2 LAST CDS_LIB standard
J 0
(-3700 5025);
DISPLAY INVISIBLE (-3700 5025);
FORCEPROP 2 LAST BOM_COST IO_SLOT
J 0
(-4200 5125);
DISPLAY 0.829787 (-4200 5125);
DISPLAY INVISIBLE (-4200 5125);
FORCEPROP 1 LAST BODY_TYPE PLUMBING
J 2
(-3700 4975);
DISPLAY 0.702128 (-3700 4975);
PAINT GREEN (-3700 4975);
DISPLAY INVISIBLE (-3700 4975);
FORCEPROP 1 LAST HDL_TAP TRUE
J 2
(-4025 4900);
DISPLAY 0.702128 (-4025 4900);
PAINT GREEN (-4025 4900);
DISPLAY INVISIBLE (-4025 4900);
FORCEPROP 1 LAST PATH I166
J 2
(-3698 5025);
DISPLAY 0.872340 (-3698 5025);
PAINT GREEN (-3698 5025);
DISPLAY INVISIBLE (-3698 5025);
FORCEPROP 2 LAST ROOM RISER1
J 0
(-4200 5075);
DISPLAY 0.829787 (-4200 5075);
PAINT RED (-4200 5075);
DISPLAY INVISIBLE (-4200 5075);
FORCEADD TAP..6
R 2
(-3850 5175);
FORCEPROP 3 LASTPIN (-3900 5175) SIG_NAME P5E_CPU0_P2_TX_DP<7>
J 0
(-3890 5185);
DISPLAY 0.659574 (-3890 5185);
PAINT MONO (-3890 5185);
DISPLAY INVISIBLE (-3890 5185);
FORCEPROP 1 LASTPIN (-3900 5175) BN 7
J 2
(-3848 5183);
DISPLAY 0.489362 (-3848 5183);
PAINT MONO (-3848 5183);
FORCEPROP 2 LAST CDS_LIB standard
J 0
(-3850 5175);
DISPLAY INVISIBLE (-3850 5175);
FORCEPROP 2 LAST BOM_COST IO_SLOT
J 0
(-4350 5275);
DISPLAY 0.829787 (-4350 5275);
DISPLAY INVISIBLE (-4350 5275);
FORCEPROP 1 LAST BODY_TYPE PLUMBING
J 2
(-3850 5125);
DISPLAY 0.702128 (-3850 5125);
PAINT GREEN (-3850 5125);
DISPLAY INVISIBLE (-3850 5125);
FORCEPROP 1 LAST HDL_TAP TRUE
J 2
(-4175 5050);
DISPLAY 0.702128 (-4175 5050);
PAINT GREEN (-4175 5050);
DISPLAY INVISIBLE (-4175 5050);
FORCEPROP 1 LAST PATH I167
J 2
(-3848 5175);
DISPLAY 0.872340 (-3848 5175);
PAINT GREEN (-3848 5175);
DISPLAY INVISIBLE (-3848 5175);
FORCEPROP 2 LAST ROOM RISER1
J 0
(-4350 5225);
DISPLAY 0.829787 (-4350 5225);
PAINT RED (-4350 5225);
DISPLAY INVISIBLE (-4350 5225);
FORCEADD TAP..6
R 2
(-3850 5075);
FORCEPROP 3 LASTPIN (-3900 5075) SIG_NAME P5E_CPU0_P2_TX_DP<8>
J 0
(-3890 5085);
DISPLAY 0.659574 (-3890 5085);
PAINT MONO (-3890 5085);
DISPLAY INVISIBLE (-3890 5085);
FORCEPROP 1 LASTPIN (-3900 5075) BN 8
J 2
(-3848 5083);
DISPLAY 0.489362 (-3848 5083);
PAINT MONO (-3848 5083);
FORCEPROP 2 LAST CDS_LIB standard
J 0
(-3850 5075);
DISPLAY INVISIBLE (-3850 5075);
FORCEPROP 2 LAST BOM_COST IO_SLOT
J 0
(-4350 5175);
DISPLAY 0.829787 (-4350 5175);
DISPLAY INVISIBLE (-4350 5175);
FORCEPROP 1 LAST BODY_TYPE PLUMBING
J 2
(-3850 5025);
DISPLAY 0.702128 (-3850 5025);
PAINT GREEN (-3850 5025);
DISPLAY INVISIBLE (-3850 5025);
FORCEPROP 1 LAST HDL_TAP TRUE
J 2
(-4175 4950);
DISPLAY 0.702128 (-4175 4950);
PAINT GREEN (-4175 4950);
DISPLAY INVISIBLE (-4175 4950);
FORCEPROP 1 LAST PATH I168
J 2
(-3848 5075);
DISPLAY 0.872340 (-3848 5075);
PAINT GREEN (-3848 5075);
DISPLAY INVISIBLE (-3848 5075);
FORCEPROP 2 LAST ROOM RISER1
J 0
(-4350 5125);
DISPLAY 0.829787 (-4350 5125);
PAINT RED (-4350 5125);
DISPLAY INVISIBLE (-4350 5125);
FORCEADD TAP..6
R 2
(-3850 4975);
FORCEPROP 3 LASTPIN (-3900 4975) SIG_NAME P5E_CPU0_P2_TX_DP<9>
J 0
(-3890 4985);
DISPLAY 0.659574 (-3890 4985);
PAINT MONO (-3890 4985);
DISPLAY INVISIBLE (-3890 4985);
FORCEPROP 1 LASTPIN (-3900 4975) BN 9
J 2
(-3848 4983);
DISPLAY 0.489362 (-3848 4983);
PAINT MONO (-3848 4983);
FORCEPROP 2 LAST CDS_LIB standard
J 0
(-3850 4975);
DISPLAY INVISIBLE (-3850 4975);
FORCEPROP 2 LAST BOM_COST IO_SLOT
J 0
(-4350 5075);
DISPLAY 0.829787 (-4350 5075);
DISPLAY INVISIBLE (-4350 5075);
FORCEPROP 1 LAST BODY_TYPE PLUMBING
J 2
(-3850 4925);
DISPLAY 0.702128 (-3850 4925);
PAINT GREEN (-3850 4925);
DISPLAY INVISIBLE (-3850 4925);
FORCEPROP 1 LAST HDL_TAP TRUE
J 2
(-4175 4850);
DISPLAY 0.702128 (-4175 4850);
PAINT GREEN (-4175 4850);
DISPLAY INVISIBLE (-4175 4850);
FORCEPROP 1 LAST PATH I169
J 2
(-3848 4975);
DISPLAY 0.872340 (-3848 4975);
PAINT GREEN (-3848 4975);
DISPLAY INVISIBLE (-3848 4975);
FORCEPROP 2 LAST ROOM RISER1
J 0
(-4350 5025);
DISPLAY 0.829787 (-4350 5025);
PAINT RED (-4350 5025);
DISPLAY INVISIBLE (-4350 5025);
FORCEADD TAP..6
R 2
(-3700 4825);
FORCEPROP 3 LASTPIN (-3750 4825) SIG_NAME P5E_CPU0_P2_TX_DN<10>
J 0
(-3740 4835);
DISPLAY 0.659574 (-3740 4835);
PAINT MONO (-3740 4835);
DISPLAY INVISIBLE (-3740 4835);
FORCEPROP 1 LASTPIN (-3750 4825) BN 10
J 2
(-3698 4833);
DISPLAY 0.489362 (-3698 4833);
PAINT MONO (-3698 4833);
FORCEPROP 2 LAST CDS_LIB standard
J 0
(-3700 4825);
DISPLAY INVISIBLE (-3700 4825);
FORCEPROP 2 LAST BOM_COST IO_SLOT
J 0
(-4200 4925);
DISPLAY 0.829787 (-4200 4925);
DISPLAY INVISIBLE (-4200 4925);
FORCEPROP 1 LAST BODY_TYPE PLUMBING
J 2
(-3700 4775);
DISPLAY 0.702128 (-3700 4775);
PAINT GREEN (-3700 4775);
DISPLAY INVISIBLE (-3700 4775);
FORCEPROP 1 LAST HDL_TAP TRUE
J 2
(-4025 4700);
DISPLAY 0.702128 (-4025 4700);
PAINT GREEN (-4025 4700);
DISPLAY INVISIBLE (-4025 4700);
FORCEPROP 1 LAST PATH I170
J 2
(-3698 4825);
DISPLAY 0.872340 (-3698 4825);
PAINT GREEN (-3698 4825);
DISPLAY INVISIBLE (-3698 4825);
FORCEPROP 2 LAST ROOM RISER1
J 0
(-4200 4875);
DISPLAY 0.829787 (-4200 4875);
PAINT RED (-4200 4875);
DISPLAY INVISIBLE (-4200 4875);
FORCEADD TAP..6
R 2
(-3700 4925);
FORCEPROP 3 LASTPIN (-3750 4925) SIG_NAME P5E_CPU0_P2_TX_DN<9>
J 0
(-3740 4935);
DISPLAY 0.659574 (-3740 4935);
PAINT MONO (-3740 4935);
DISPLAY INVISIBLE (-3740 4935);
FORCEPROP 1 LASTPIN (-3750 4925) BN 9
J 2
(-3698 4933);
DISPLAY 0.489362 (-3698 4933);
PAINT MONO (-3698 4933);
FORCEPROP 2 LAST CDS_LIB standard
J 0
(-3700 4925);
DISPLAY INVISIBLE (-3700 4925);
FORCEPROP 2 LAST BOM_COST IO_SLOT
J 0
(-4200 5025);
DISPLAY 0.829787 (-4200 5025);
DISPLAY INVISIBLE (-4200 5025);
FORCEPROP 1 LAST BODY_TYPE PLUMBING
J 2
(-3700 4875);
DISPLAY 0.702128 (-3700 4875);
PAINT GREEN (-3700 4875);
DISPLAY INVISIBLE (-3700 4875);
FORCEPROP 1 LAST HDL_TAP TRUE
J 2
(-4025 4800);
DISPLAY 0.702128 (-4025 4800);
PAINT GREEN (-4025 4800);
DISPLAY INVISIBLE (-4025 4800);
FORCEPROP 1 LAST PATH I171
J 2
(-3698 4925);
DISPLAY 0.872340 (-3698 4925);
PAINT GREEN (-3698 4925);
DISPLAY INVISIBLE (-3698 4925);
FORCEPROP 2 LAST ROOM RISER1
J 0
(-4200 4975);
DISPLAY 0.829787 (-4200 4975);
PAINT RED (-4200 4975);
DISPLAY INVISIBLE (-4200 4975);
FORCEADD TAP..6
R 2
(-3700 4725);
FORCEPROP 3 LASTPIN (-3750 4725) SIG_NAME P5E_CPU0_P2_TX_DN<11>
J 0
(-3740 4735);
DISPLAY 0.659574 (-3740 4735);
PAINT MONO (-3740 4735);
DISPLAY INVISIBLE (-3740 4735);
FORCEPROP 1 LASTPIN (-3750 4725) BN 11
J 2
(-3698 4733);
DISPLAY 0.489362 (-3698 4733);
PAINT MONO (-3698 4733);
FORCEPROP 2 LAST CDS_LIB standard
J 0
(-3700 4725);
DISPLAY INVISIBLE (-3700 4725);
FORCEPROP 2 LAST BOM_COST IO_SLOT
J 0
(-4200 4825);
DISPLAY 0.829787 (-4200 4825);
DISPLAY INVISIBLE (-4200 4825);
FORCEPROP 1 LAST BODY_TYPE PLUMBING
J 2
(-3700 4675);
DISPLAY 0.702128 (-3700 4675);
PAINT GREEN (-3700 4675);
DISPLAY INVISIBLE (-3700 4675);
FORCEPROP 1 LAST HDL_TAP TRUE
J 2
(-4025 4600);
DISPLAY 0.702128 (-4025 4600);
PAINT GREEN (-4025 4600);
DISPLAY INVISIBLE (-4025 4600);
FORCEPROP 1 LAST PATH I172
J 2
(-3698 4725);
DISPLAY 0.872340 (-3698 4725);
PAINT GREEN (-3698 4725);
DISPLAY INVISIBLE (-3698 4725);
FORCEPROP 2 LAST ROOM RISER1
J 0
(-4200 4775);
DISPLAY 0.829787 (-4200 4775);
PAINT RED (-4200 4775);
DISPLAY INVISIBLE (-4200 4775);
FORCEADD TAP..6
R 2
(-3850 4875);
FORCEPROP 3 LASTPIN (-3900 4875) SIG_NAME P5E_CPU0_P2_TX_DP<10>
J 0
(-3890 4885);
DISPLAY 0.659574 (-3890 4885);
PAINT MONO (-3890 4885);
DISPLAY INVISIBLE (-3890 4885);
FORCEPROP 1 LASTPIN (-3900 4875) BN 10
J 2
(-3848 4883);
DISPLAY 0.489362 (-3848 4883);
PAINT MONO (-3848 4883);
FORCEPROP 2 LAST CDS_LIB standard
J 0
(-3850 4875);
DISPLAY INVISIBLE (-3850 4875);
FORCEPROP 2 LAST BOM_COST IO_SLOT
J 0
(-4350 4975);
DISPLAY 0.829787 (-4350 4975);
DISPLAY INVISIBLE (-4350 4975);
FORCEPROP 1 LAST BODY_TYPE PLUMBING
J 2
(-3850 4825);
DISPLAY 0.702128 (-3850 4825);
PAINT GREEN (-3850 4825);
DISPLAY INVISIBLE (-3850 4825);
FORCEPROP 1 LAST HDL_TAP TRUE
J 2
(-4175 4750);
DISPLAY 0.702128 (-4175 4750);
PAINT GREEN (-4175 4750);
DISPLAY INVISIBLE (-4175 4750);
FORCEPROP 1 LAST PATH I173
J 2
(-3848 4875);
DISPLAY 0.872340 (-3848 4875);
PAINT GREEN (-3848 4875);
DISPLAY INVISIBLE (-3848 4875);
FORCEPROP 2 LAST ROOM RISER1
J 0
(-4350 4925);
DISPLAY 0.829787 (-4350 4925);
PAINT RED (-4350 4925);
DISPLAY INVISIBLE (-4350 4925);
FORCEADD TAP..6
R 2
(-3850 4775);
FORCEPROP 3 LASTPIN (-3900 4775) SIG_NAME P5E_CPU0_P2_TX_DP<11>
J 0
(-3890 4785);
DISPLAY 0.659574 (-3890 4785);
PAINT MONO (-3890 4785);
DISPLAY INVISIBLE (-3890 4785);
FORCEPROP 1 LASTPIN (-3900 4775) BN 11
J 2
(-3848 4783);
DISPLAY 0.489362 (-3848 4783);
PAINT MONO (-3848 4783);
FORCEPROP 2 LAST CDS_LIB standard
J 0
(-3850 4775);
DISPLAY INVISIBLE (-3850 4775);
FORCEPROP 2 LAST BOM_COST IO_SLOT
J 0
(-4350 4875);
DISPLAY 0.829787 (-4350 4875);
DISPLAY INVISIBLE (-4350 4875);
FORCEPROP 1 LAST BODY_TYPE PLUMBING
J 2
(-3850 4725);
DISPLAY 0.702128 (-3850 4725);
PAINT GREEN (-3850 4725);
DISPLAY INVISIBLE (-3850 4725);
FORCEPROP 1 LAST HDL_TAP TRUE
J 2
(-4175 4650);
DISPLAY 0.702128 (-4175 4650);
PAINT GREEN (-4175 4650);
DISPLAY INVISIBLE (-4175 4650);
FORCEPROP 1 LAST PATH I174
J 2
(-3848 4775);
DISPLAY 0.872340 (-3848 4775);
PAINT GREEN (-3848 4775);
DISPLAY INVISIBLE (-3848 4775);
FORCEPROP 2 LAST ROOM RISER1
J 0
(-4350 4825);
DISPLAY 0.829787 (-4350 4825);
PAINT RED (-4350 4825);
DISPLAY INVISIBLE (-4350 4825);
FORCEADD TAP..6
R 2
(-3700 4625);
FORCEPROP 3 LASTPIN (-3750 4625) SIG_NAME P5E_CPU0_P2_TX_DN<12>
J 0
(-3740 4635);
DISPLAY 0.659574 (-3740 4635);
PAINT MONO (-3740 4635);
DISPLAY INVISIBLE (-3740 4635);
FORCEPROP 1 LASTPIN (-3750 4625) BN 12
J 2
(-3698 4633);
DISPLAY 0.489362 (-3698 4633);
PAINT MONO (-3698 4633);
FORCEPROP 2 LAST CDS_LIB standard
J 0
(-3700 4625);
DISPLAY INVISIBLE (-3700 4625);
FORCEPROP 2 LAST BOM_COST IO_SLOT
J 0
(-4200 4725);
DISPLAY 0.829787 (-4200 4725);
DISPLAY INVISIBLE (-4200 4725);
FORCEPROP 1 LAST BODY_TYPE PLUMBING
J 2
(-3700 4575);
DISPLAY 0.702128 (-3700 4575);
PAINT GREEN (-3700 4575);
DISPLAY INVISIBLE (-3700 4575);
FORCEPROP 1 LAST HDL_TAP TRUE
J 2
(-4025 4500);
DISPLAY 0.702128 (-4025 4500);
PAINT GREEN (-4025 4500);
DISPLAY INVISIBLE (-4025 4500);
FORCEPROP 1 LAST PATH I175
J 2
(-3698 4625);
DISPLAY 0.872340 (-3698 4625);
PAINT GREEN (-3698 4625);
DISPLAY INVISIBLE (-3698 4625);
FORCEPROP 2 LAST ROOM RISER1
J 0
(-4200 4675);
DISPLAY 0.829787 (-4200 4675);
PAINT RED (-4200 4675);
DISPLAY INVISIBLE (-4200 4675);
FORCEADD TAP..6
R 2
(-3700 4525);
FORCEPROP 3 LASTPIN (-3750 4525) SIG_NAME P5E_CPU0_P2_TX_DN<13>
J 0
(-3740 4535);
DISPLAY 0.659574 (-3740 4535);
PAINT MONO (-3740 4535);
DISPLAY INVISIBLE (-3740 4535);
FORCEPROP 1 LASTPIN (-3750 4525) BN 13
J 2
(-3698 4533);
DISPLAY 0.489362 (-3698 4533);
PAINT MONO (-3698 4533);
FORCEPROP 2 LAST CDS_LIB standard
J 0
(-3700 4525);
DISPLAY INVISIBLE (-3700 4525);
FORCEPROP 2 LAST BOM_COST IO_SLOT
J 0
(-4200 4625);
DISPLAY 0.829787 (-4200 4625);
DISPLAY INVISIBLE (-4200 4625);
FORCEPROP 1 LAST BODY_TYPE PLUMBING
J 2
(-3700 4475);
DISPLAY 0.702128 (-3700 4475);
PAINT GREEN (-3700 4475);
DISPLAY INVISIBLE (-3700 4475);
FORCEPROP 1 LAST HDL_TAP TRUE
J 2
(-4025 4400);
DISPLAY 0.702128 (-4025 4400);
PAINT GREEN (-4025 4400);
DISPLAY INVISIBLE (-4025 4400);
FORCEPROP 1 LAST PATH I176
J 2
(-3698 4525);
DISPLAY 0.872340 (-3698 4525);
PAINT GREEN (-3698 4525);
DISPLAY INVISIBLE (-3698 4525);
FORCEPROP 2 LAST ROOM RISER1
J 0
(-4200 4575);
DISPLAY 0.829787 (-4200 4575);
PAINT RED (-4200 4575);
DISPLAY INVISIBLE (-4200 4575);
FORCEADD TAP..6
R 2
(-3850 4575);
FORCEPROP 3 LASTPIN (-3900 4575) SIG_NAME P5E_CPU0_P2_TX_DP<13>
J 0
(-3890 4585);
DISPLAY 0.659574 (-3890 4585);
PAINT MONO (-3890 4585);
DISPLAY INVISIBLE (-3890 4585);
FORCEPROP 1 LASTPIN (-3900 4575) BN 13
J 2
(-3848 4583);
DISPLAY 0.489362 (-3848 4583);
PAINT MONO (-3848 4583);
FORCEPROP 2 LAST CDS_LIB standard
J 0
(-3850 4575);
DISPLAY INVISIBLE (-3850 4575);
FORCEPROP 2 LAST BOM_COST IO_SLOT
J 0
(-4350 4675);
DISPLAY 0.829787 (-4350 4675);
DISPLAY INVISIBLE (-4350 4675);
FORCEPROP 1 LAST BODY_TYPE PLUMBING
J 2
(-3850 4525);
DISPLAY 0.702128 (-3850 4525);
PAINT GREEN (-3850 4525);
DISPLAY INVISIBLE (-3850 4525);
FORCEPROP 1 LAST HDL_TAP TRUE
J 2
(-4175 4450);
DISPLAY 0.702128 (-4175 4450);
PAINT GREEN (-4175 4450);
DISPLAY INVISIBLE (-4175 4450);
FORCEPROP 1 LAST PATH I177
J 2
(-3848 4575);
DISPLAY 0.872340 (-3848 4575);
PAINT GREEN (-3848 4575);
DISPLAY INVISIBLE (-3848 4575);
FORCEPROP 2 LAST ROOM RISER1
J 0
(-4350 4625);
DISPLAY 0.829787 (-4350 4625);
PAINT RED (-4350 4625);
DISPLAY INVISIBLE (-4350 4625);
FORCEADD TAP..6
R 2
(-3850 4675);
FORCEPROP 3 LASTPIN (-3900 4675) SIG_NAME P5E_CPU0_P2_TX_DP<12>
J 0
(-3890 4685);
DISPLAY 0.659574 (-3890 4685);
PAINT MONO (-3890 4685);
DISPLAY INVISIBLE (-3890 4685);
FORCEPROP 1 LASTPIN (-3900 4675) BN 12
J 2
(-3848 4683);
DISPLAY 0.489362 (-3848 4683);
PAINT MONO (-3848 4683);
FORCEPROP 2 LAST CDS_LIB standard
J 0
(-3850 4675);
DISPLAY INVISIBLE (-3850 4675);
FORCEPROP 2 LAST BOM_COST IO_SLOT
J 0
(-4350 4775);
DISPLAY 0.829787 (-4350 4775);
DISPLAY INVISIBLE (-4350 4775);
FORCEPROP 1 LAST BODY_TYPE PLUMBING
J 2
(-3850 4625);
DISPLAY 0.702128 (-3850 4625);
PAINT GREEN (-3850 4625);
DISPLAY INVISIBLE (-3850 4625);
FORCEPROP 1 LAST HDL_TAP TRUE
J 2
(-4175 4550);
DISPLAY 0.702128 (-4175 4550);
PAINT GREEN (-4175 4550);
DISPLAY INVISIBLE (-4175 4550);
FORCEPROP 1 LAST PATH I178
J 2
(-3848 4675);
DISPLAY 0.872340 (-3848 4675);
PAINT GREEN (-3848 4675);
DISPLAY INVISIBLE (-3848 4675);
FORCEPROP 2 LAST ROOM RISER1
J 0
(-4350 4725);
DISPLAY 0.829787 (-4350 4725);
PAINT RED (-4350 4725);
DISPLAY INVISIBLE (-4350 4725);
FORCEADD TAP..6
R 2
(-3850 4475);
FORCEPROP 3 LASTPIN (-3900 4475) SIG_NAME P5E_CPU0_P2_TX_DP<14>
J 0
(-3890 4485);
DISPLAY 0.659574 (-3890 4485);
PAINT MONO (-3890 4485);
DISPLAY INVISIBLE (-3890 4485);
FORCEPROP 1 LASTPIN (-3900 4475) BN 14
J 2
(-3848 4483);
DISPLAY 0.489362 (-3848 4483);
PAINT MONO (-3848 4483);
FORCEPROP 2 LAST CDS_LIB standard
J 0
(-3850 4475);
DISPLAY INVISIBLE (-3850 4475);
FORCEPROP 2 LAST BOM_COST IO_SLOT
J 0
(-4350 4575);
DISPLAY 0.829787 (-4350 4575);
DISPLAY INVISIBLE (-4350 4575);
FORCEPROP 1 LAST BODY_TYPE PLUMBING
J 2
(-3850 4425);
DISPLAY 0.702128 (-3850 4425);
PAINT GREEN (-3850 4425);
DISPLAY INVISIBLE (-3850 4425);
FORCEPROP 1 LAST HDL_TAP TRUE
J 2
(-4175 4350);
DISPLAY 0.702128 (-4175 4350);
PAINT GREEN (-4175 4350);
DISPLAY INVISIBLE (-4175 4350);
FORCEPROP 1 LAST PATH I179
J 2
(-3848 4475);
DISPLAY 0.872340 (-3848 4475);
PAINT GREEN (-3848 4475);
DISPLAY INVISIBLE (-3848 4475);
FORCEPROP 2 LAST ROOM RISER1
J 0
(-4350 4525);
DISPLAY 0.829787 (-4350 4525);
PAINT RED (-4350 4525);
DISPLAY INVISIBLE (-4350 4525);
FORCEADD TAP..6
R 2
(-3700 4325);
FORCEPROP 3 LASTPIN (-3750 4325) SIG_NAME P5E_CPU0_P2_TX_DN<15>
J 0
(-3740 4335);
DISPLAY 0.659574 (-3740 4335);
PAINT MONO (-3740 4335);
DISPLAY INVISIBLE (-3740 4335);
FORCEPROP 1 LASTPIN (-3750 4325) BN 15
J 2
(-3698 4333);
DISPLAY 0.489362 (-3698 4333);
PAINT MONO (-3698 4333);
FORCEPROP 2 LAST CDS_LIB standard
J 0
(-3700 4325);
DISPLAY INVISIBLE (-3700 4325);
FORCEPROP 2 LAST BOM_COST IO_SLOT
J 0
(-4200 4425);
DISPLAY 0.829787 (-4200 4425);
DISPLAY INVISIBLE (-4200 4425);
FORCEPROP 1 LAST BODY_TYPE PLUMBING
J 2
(-3700 4275);
DISPLAY 0.702128 (-3700 4275);
PAINT GREEN (-3700 4275);
DISPLAY INVISIBLE (-3700 4275);
FORCEPROP 1 LAST HDL_TAP TRUE
J 2
(-4025 4200);
DISPLAY 0.702128 (-4025 4200);
PAINT GREEN (-4025 4200);
DISPLAY INVISIBLE (-4025 4200);
FORCEPROP 1 LAST PATH I180
J 2
(-3698 4325);
DISPLAY 0.872340 (-3698 4325);
PAINT GREEN (-3698 4325);
DISPLAY INVISIBLE (-3698 4325);
FORCEPROP 2 LAST ROOM RISER1
J 0
(-4200 4375);
DISPLAY 0.829787 (-4200 4375);
PAINT RED (-4200 4375);
DISPLAY INVISIBLE (-4200 4375);
FORCEADD TAP..6
R 2
(-3700 4425);
FORCEPROP 3 LASTPIN (-3750 4425) SIG_NAME P5E_CPU0_P2_TX_DN<14>
J 0
(-3740 4435);
DISPLAY 0.659574 (-3740 4435);
PAINT MONO (-3740 4435);
DISPLAY INVISIBLE (-3740 4435);
FORCEPROP 1 LASTPIN (-3750 4425) BN 14
J 2
(-3698 4433);
DISPLAY 0.489362 (-3698 4433);
PAINT MONO (-3698 4433);
FORCEPROP 2 LAST BOM_COST IO_SLOT
J 0
(-4200 4525);
DISPLAY 0.829787 (-4200 4525);
DISPLAY INVISIBLE (-4200 4525);
FORCEPROP 2 LAST CDS_LIB standard
J 0
(-3700 4425);
DISPLAY INVISIBLE (-3700 4425);
FORCEPROP 1 LAST BODY_TYPE PLUMBING
J 2
(-3700 4375);
DISPLAY 0.702128 (-3700 4375);
PAINT GREEN (-3700 4375);
DISPLAY INVISIBLE (-3700 4375);
FORCEPROP 1 LAST HDL_TAP TRUE
J 2
(-4025 4300);
DISPLAY 0.702128 (-4025 4300);
PAINT GREEN (-4025 4300);
DISPLAY INVISIBLE (-4025 4300);
FORCEPROP 1 LAST PATH I181
J 2
(-3698 4425);
DISPLAY 0.872340 (-3698 4425);
PAINT GREEN (-3698 4425);
DISPLAY INVISIBLE (-3698 4425);
FORCEPROP 2 LAST ROOM RISER1
J 0
(-4200 4475);
DISPLAY 0.829787 (-4200 4475);
PAINT RED (-4200 4475);
DISPLAY INVISIBLE (-4200 4475);
FORCEADD TAP..6
R 2
(-3850 4375);
FORCEPROP 3 LASTPIN (-3900 4375) SIG_NAME P5E_CPU0_P2_TX_DP<15>
J 0
(-3890 4385);
DISPLAY 0.659574 (-3890 4385);
PAINT MONO (-3890 4385);
DISPLAY INVISIBLE (-3890 4385);
FORCEPROP 1 LASTPIN (-3900 4375) BN 15
J 2
(-3848 4383);
DISPLAY 0.489362 (-3848 4383);
PAINT MONO (-3848 4383);
FORCEPROP 2 LAST CDS_LIB standard
J 0
(-3850 4375);
DISPLAY INVISIBLE (-3850 4375);
FORCEPROP 2 LAST BOM_COST IO_SLOT
J 0
(-4350 4475);
DISPLAY 0.829787 (-4350 4475);
DISPLAY INVISIBLE (-4350 4475);
FORCEPROP 1 LAST BODY_TYPE PLUMBING
J 2
(-3850 4325);
DISPLAY 0.702128 (-3850 4325);
PAINT GREEN (-3850 4325);
DISPLAY INVISIBLE (-3850 4325);
FORCEPROP 1 LAST HDL_TAP TRUE
J 2
(-4175 4250);
DISPLAY 0.702128 (-4175 4250);
PAINT GREEN (-4175 4250);
DISPLAY INVISIBLE (-4175 4250);
FORCEPROP 1 LAST PATH I182
J 2
(-3848 4375);
DISPLAY 0.872340 (-3848 4375);
PAINT GREEN (-3848 4375);
DISPLAY INVISIBLE (-3848 4375);
FORCEPROP 2 LAST ROOM RISER1
J 0
(-4350 4425);
DISPLAY 0.829787 (-4350 4425);
PAINT RED (-4350 4425);
DISPLAY INVISIBLE (-4350 4425);
FORCEADD OFFPAGE..2
(-2725 3050);
FORCEPROP 2 LAST $XR0 117 
J 0
(-2536 3050);
DISPLAY 0.638298 (-2536 3050);
PAINT MONO (-2536 3050);
FORCEPROP 2 LAST PATH I217
J 0
(-2425 3100);
DISPLAY 1.021277 (-2425 3100);
DISPLAY INVISIBLE (-2425 3100);
FORCEPROP 1 LAST COMMENT_BODY TRUE
J 0
(-2770 2955);
DISPLAY 0.872340 (-2770 2955);
PAINT GREEN (-2770 2955);
DISPLAY INVISIBLE (-2770 2955);
FORCEPROP 1 LAST OFFPAGE TRUE
J 0
(-2400 2925);
DISPLAY 0.872340 (-2400 2925);
PAINT GREEN (-2400 2925);
DISPLAY INVISIBLE (-2400 2925);
FORCEPROP 2 LAST CDS_LIB standard
J 0
(-2725 3050);
DISPLAY INVISIBLE (-2725 3050);
FORCEADD OFFPAGE..2
(-2725 3000);
FORCEPROP 2 LAST $XR0 117 
J 0
(-2536 3000);
DISPLAY 0.638298 (-2536 3000);
PAINT MONO (-2536 3000);
FORCEPROP 2 LAST PATH I218
J 0
(-2425 3050);
DISPLAY 1.021277 (-2425 3050);
DISPLAY INVISIBLE (-2425 3050);
FORCEPROP 1 LAST COMMENT_BODY TRUE
J 0
(-2770 2905);
DISPLAY 0.872340 (-2770 2905);
PAINT GREEN (-2770 2905);
DISPLAY INVISIBLE (-2770 2905);
FORCEPROP 1 LAST OFFPAGE TRUE
J 0
(-2400 2875);
DISPLAY 0.872340 (-2400 2875);
PAINT GREEN (-2400 2875);
DISPLAY INVISIBLE (-2400 2875);
FORCEPROP 2 LAST CDS_LIB standard
J 0
(-2725 3000);
DISPLAY INVISIBLE (-2725 3000);
FORCEADD OFFPAGE..1
(-7375 3000);
FORCEPROP 2 LAST $XR0 117 
J 0
(-7627 3000);
DISPLAY 0.638298 (-7627 3000);
PAINT MONO (-7627 3000);
FORCEPROP 2 LAST PATH I283
J 0
(-7575 3050);
DISPLAY 1.021277 (-7575 3050);
DISPLAY INVISIBLE (-7575 3050);
FORCEPROP 1 LAST COMMENT_BODY TRUE
J 0
(-7250 2900);
DISPLAY 0.872340 (-7250 2900);
PAINT GREEN (-7250 2900);
DISPLAY INVISIBLE (-7250 2900);
FORCEPROP 1 LAST OFFPAGE TRUE
J 0
(-7050 2875);
DISPLAY 0.872340 (-7050 2875);
PAINT GREEN (-7050 2875);
DISPLAY INVISIBLE (-7050 2875);
FORCEPROP 2 LAST CDS_LIB standard
J 0
(-7375 3000);
DISPLAY INVISIBLE (-7375 3000);
FORCEADD OFFPAGE..1
(-7375 3050);
FORCEPROP 2 LAST $XR0 117 
J 0
(-7627 3050);
DISPLAY 0.638298 (-7627 3050);
PAINT MONO (-7627 3050);
FORCEPROP 2 LAST PATH I284
J 0
(-7575 3100);
DISPLAY 1.021277 (-7575 3100);
DISPLAY INVISIBLE (-7575 3100);
FORCEPROP 1 LAST COMMENT_BODY TRUE
J 0
(-7250 2950);
DISPLAY 0.872340 (-7250 2950);
PAINT GREEN (-7250 2950);
DISPLAY INVISIBLE (-7250 2950);
FORCEPROP 1 LAST OFFPAGE TRUE
J 0
(-7050 2925);
DISPLAY 0.872340 (-7050 2925);
PAINT GREEN (-7050 2925);
DISPLAY INVISIBLE (-7050 2925);
FORCEPROP 2 LAST CDS_LIB standard
J 0
(-7375 3050);
DISPLAY INVISIBLE (-7375 3050);
FORCEADD TAP..6
R 2
(-3850 2350);
FORCEPROP 3 LASTPIN (-3900 2350) SIG_NAME P5E_CPU0_P3_TX_DP<7>
J 0
(-3890 2360);
DISPLAY 0.659574 (-3890 2360);
PAINT MONO (-3890 2360);
DISPLAY INVISIBLE (-3890 2360);
FORCEPROP 1 LASTPIN (-3900 2350) BN 7
J 2
(-3848 2358);
DISPLAY 0.489362 (-3848 2358);
PAINT MONO (-3848 2358);
FORCEPROP 2 LAST BOM_COST IO_SLOT
J 0
(-4350 2450);
DISPLAY 0.829787 (-4350 2450);
DISPLAY INVISIBLE (-4350 2450);
FORCEPROP 2 LAST CDS_LIB standard
J 0
(-3850 2350);
DISPLAY INVISIBLE (-3850 2350);
FORCEPROP 1 LAST BODY_TYPE PLUMBING
J 2
(-3850 2300);
DISPLAY 0.702128 (-3850 2300);
PAINT GREEN (-3850 2300);
DISPLAY INVISIBLE (-3850 2300);
FORCEPROP 1 LAST HDL_TAP TRUE
J 2
(-4175 2225);
DISPLAY 0.702128 (-4175 2225);
PAINT GREEN (-4175 2225);
DISPLAY INVISIBLE (-4175 2225);
FORCEPROP 1 LAST PATH I285
J 2
(-3848 2350);
DISPLAY 0.872340 (-3848 2350);
PAINT GREEN (-3848 2350);
DISPLAY INVISIBLE (-3848 2350);
FORCEPROP 2 LAST ROOM RISER1
J 0
(-4350 2400);
DISPLAY 0.829787 (-4350 2400);
PAINT RED (-4350 2400);
DISPLAY INVISIBLE (-4350 2400);
FORCEADD TAP..6
R 2
(-3850 2450);
FORCEPROP 3 LASTPIN (-3900 2450) SIG_NAME P5E_CPU0_P3_TX_DP<6>
J 0
(-3890 2460);
DISPLAY 0.659574 (-3890 2460);
PAINT MONO (-3890 2460);
DISPLAY INVISIBLE (-3890 2460);
FORCEPROP 1 LASTPIN (-3900 2450) BN 6
J 2
(-3848 2458);
DISPLAY 0.489362 (-3848 2458);
PAINT MONO (-3848 2458);
FORCEPROP 2 LAST BOM_COST IO_SLOT
J 0
(-4350 2550);
DISPLAY 0.829787 (-4350 2550);
DISPLAY INVISIBLE (-4350 2550);
FORCEPROP 2 LAST CDS_LIB standard
J 0
(-3850 2450);
DISPLAY INVISIBLE (-3850 2450);
FORCEPROP 1 LAST BODY_TYPE PLUMBING
J 2
(-3850 2400);
DISPLAY 0.702128 (-3850 2400);
PAINT GREEN (-3850 2400);
DISPLAY INVISIBLE (-3850 2400);
FORCEPROP 1 LAST HDL_TAP TRUE
J 2
(-4175 2325);
DISPLAY 0.702128 (-4175 2325);
PAINT GREEN (-4175 2325);
DISPLAY INVISIBLE (-4175 2325);
FORCEPROP 1 LAST PATH I286
J 2
(-3848 2450);
DISPLAY 0.872340 (-3848 2450);
PAINT GREEN (-3848 2450);
DISPLAY INVISIBLE (-3848 2450);
FORCEPROP 2 LAST ROOM RISER1
J 0
(-4350 2500);
DISPLAY 0.829787 (-4350 2500);
PAINT RED (-4350 2500);
DISPLAY INVISIBLE (-4350 2500);
FORCEADD TAP..6
R 2
(-3850 2650);
FORCEPROP 3 LASTPIN (-3900 2650) SIG_NAME P5E_CPU0_P3_TX_DP<4>
J 0
(-3890 2660);
DISPLAY 0.659574 (-3890 2660);
PAINT MONO (-3890 2660);
DISPLAY INVISIBLE (-3890 2660);
FORCEPROP 1 LASTPIN (-3900 2650) BN 4
J 2
(-3848 2658);
DISPLAY 0.489362 (-3848 2658);
PAINT MONO (-3848 2658);
FORCEPROP 2 LAST BOM_COST IO_SLOT
J 0
(-4350 2750);
DISPLAY 0.829787 (-4350 2750);
DISPLAY INVISIBLE (-4350 2750);
FORCEPROP 2 LAST CDS_LIB standard
J 0
(-3850 2650);
DISPLAY INVISIBLE (-3850 2650);
FORCEPROP 1 LAST BODY_TYPE PLUMBING
J 2
(-3850 2600);
DISPLAY 0.702128 (-3850 2600);
PAINT GREEN (-3850 2600);
DISPLAY INVISIBLE (-3850 2600);
FORCEPROP 1 LAST HDL_TAP TRUE
J 2
(-4175 2525);
DISPLAY 0.702128 (-4175 2525);
PAINT GREEN (-4175 2525);
DISPLAY INVISIBLE (-4175 2525);
FORCEPROP 1 LAST PATH I287
J 2
(-3848 2650);
DISPLAY 0.872340 (-3848 2650);
PAINT GREEN (-3848 2650);
DISPLAY INVISIBLE (-3848 2650);
FORCEPROP 2 LAST ROOM RISER1
J 0
(-4350 2700);
DISPLAY 0.829787 (-4350 2700);
PAINT RED (-4350 2700);
DISPLAY INVISIBLE (-4350 2700);
FORCEADD TAP..6
R 2
(-3850 2550);
FORCEPROP 3 LASTPIN (-3900 2550) SIG_NAME P5E_CPU0_P3_TX_DP<5>
J 0
(-3890 2560);
DISPLAY 0.659574 (-3890 2560);
PAINT MONO (-3890 2560);
DISPLAY INVISIBLE (-3890 2560);
FORCEPROP 1 LASTPIN (-3900 2550) BN 5
J 2
(-3848 2558);
DISPLAY 0.489362 (-3848 2558);
PAINT MONO (-3848 2558);
FORCEPROP 2 LAST BOM_COST IO_SLOT
J 0
(-4350 2650);
DISPLAY 0.829787 (-4350 2650);
DISPLAY INVISIBLE (-4350 2650);
FORCEPROP 2 LAST CDS_LIB standard
J 0
(-3850 2550);
DISPLAY INVISIBLE (-3850 2550);
FORCEPROP 1 LAST BODY_TYPE PLUMBING
J 2
(-3850 2500);
DISPLAY 0.702128 (-3850 2500);
PAINT GREEN (-3850 2500);
DISPLAY INVISIBLE (-3850 2500);
FORCEPROP 1 LAST HDL_TAP TRUE
J 2
(-4175 2425);
DISPLAY 0.702128 (-4175 2425);
PAINT GREEN (-4175 2425);
DISPLAY INVISIBLE (-4175 2425);
FORCEPROP 1 LAST PATH I288
J 2
(-3848 2550);
DISPLAY 0.872340 (-3848 2550);
PAINT GREEN (-3848 2550);
DISPLAY INVISIBLE (-3848 2550);
FORCEPROP 2 LAST ROOM RISER1
J 0
(-4350 2600);
DISPLAY 0.829787 (-4350 2600);
PAINT RED (-4350 2600);
DISPLAY INVISIBLE (-4350 2600);
FORCEADD OFFPAGE..1
(-7375 2675);
FORCEPROP 2 LAST $XR0 117 
J 0
(-7627 2675);
DISPLAY 0.638298 (-7627 2675);
PAINT MONO (-7627 2675);
FORCEPROP 2 LAST CDS_LIB standard
J 0
(-7375 2675);
DISPLAY INVISIBLE (-7375 2675);
FORCEPROP 1 LAST OFFPAGE TRUE
J 0
(-7050 2550);
DISPLAY 0.872340 (-7050 2550);
PAINT GREEN (-7050 2550);
DISPLAY INVISIBLE (-7050 2550);
FORCEPROP 1 LAST COMMENT_BODY TRUE
J 0
(-7250 2575);
DISPLAY 0.872340 (-7250 2575);
PAINT GREEN (-7250 2575);
DISPLAY INVISIBLE (-7250 2575);
FORCEPROP 2 LAST PATH I293
J 0
(-7325 2750);
DISPLAY 1.021277 (-7325 2750);
DISPLAY INVISIBLE (-7325 2750);
FORCEADD TAP..6
(-6275 2350);
FORCEPROP 3 LASTPIN (-6225 2350) SIG_NAME P5E_CPU0_P3_RX_DP<7>
J 0
(-6215 2360);
DISPLAY 0.659574 (-6215 2360);
PAINT MONO (-6215 2360);
DISPLAY INVISIBLE (-6215 2360);
FORCEPROP 1 LASTPIN (-6225 2350) BN 7
J 0
(-6277 2358);
DISPLAY 0.489362 (-6277 2358);
PAINT MONO (-6277 2358);
FORCEPROP 2 LAST CDS_LIB standard
J 0
(-6275 2350);
DISPLAY INVISIBLE (-6275 2350);
FORCEPROP 1 LAST BODY_TYPE PLUMBING
J 0
(-6275 2300);
DISPLAY 0.574468 (-6275 2300);
PAINT GREEN (-6275 2300);
DISPLAY INVISIBLE (-6275 2300);
FORCEPROP 1 LAST HDL_TAP TRUE
J 0
(-5950 2225);
DISPLAY 0.574468 (-5950 2225);
PAINT GREEN (-5950 2225);
DISPLAY INVISIBLE (-5950 2225);
FORCEPROP 1 LAST PATH I299
J 0
(-6277 2350);
DISPLAY 0.872340 (-6277 2350);
PAINT GREEN (-6277 2350);
DISPLAY INVISIBLE (-6277 2350);
FORCEADD TAP..6
(-6275 2450);
FORCEPROP 3 LASTPIN (-6225 2450) SIG_NAME P5E_CPU0_P3_RX_DP<6>
J 0
(-6215 2460);
DISPLAY 0.659574 (-6215 2460);
PAINT MONO (-6215 2460);
DISPLAY INVISIBLE (-6215 2460);
FORCEPROP 1 LASTPIN (-6225 2450) BN 6
J 0
(-6277 2458);
DISPLAY 0.489362 (-6277 2458);
PAINT MONO (-6277 2458);
FORCEPROP 2 LAST CDS_LIB standard
J 0
(-6275 2450);
DISPLAY INVISIBLE (-6275 2450);
FORCEPROP 1 LAST BODY_TYPE PLUMBING
J 0
(-6275 2400);
DISPLAY 0.574468 (-6275 2400);
PAINT GREEN (-6275 2400);
DISPLAY INVISIBLE (-6275 2400);
FORCEPROP 1 LAST HDL_TAP TRUE
J 0
(-5950 2325);
DISPLAY 0.574468 (-5950 2325);
PAINT GREEN (-5950 2325);
DISPLAY INVISIBLE (-5950 2325);
FORCEPROP 1 LAST PATH I300
J 0
(-6277 2450);
DISPLAY 0.872340 (-6277 2450);
PAINT GREEN (-6277 2450);
DISPLAY INVISIBLE (-6277 2450);
FORCEADD TAP..6
(-6275 2650);
FORCEPROP 3 LASTPIN (-6225 2650) SIG_NAME P5E_CPU0_P3_RX_DP<4>
J 0
(-6215 2660);
DISPLAY 0.659574 (-6215 2660);
PAINT MONO (-6215 2660);
DISPLAY INVISIBLE (-6215 2660);
FORCEPROP 1 LASTPIN (-6225 2650) BN 4
J 0
(-6277 2658);
DISPLAY 0.489362 (-6277 2658);
PAINT MONO (-6277 2658);
FORCEPROP 2 LAST CDS_LIB standard
J 0
(-6275 2650);
DISPLAY INVISIBLE (-6275 2650);
FORCEPROP 1 LAST BODY_TYPE PLUMBING
J 0
(-6275 2600);
DISPLAY 0.574468 (-6275 2600);
PAINT GREEN (-6275 2600);
DISPLAY INVISIBLE (-6275 2600);
FORCEPROP 1 LAST HDL_TAP TRUE
J 0
(-5950 2525);
DISPLAY 0.574468 (-5950 2525);
PAINT GREEN (-5950 2525);
DISPLAY INVISIBLE (-5950 2525);
FORCEPROP 1 LAST PATH I301
J 0
(-6277 2650);
DISPLAY 0.872340 (-6277 2650);
PAINT GREEN (-6277 2650);
DISPLAY INVISIBLE (-6277 2650);
FORCEADD TAP..6
(-6275 2550);
FORCEPROP 3 LASTPIN (-6225 2550) SIG_NAME P5E_CPU0_P3_RX_DP<5>
J 0
(-6215 2560);
DISPLAY 0.659574 (-6215 2560);
PAINT MONO (-6215 2560);
DISPLAY INVISIBLE (-6215 2560);
FORCEPROP 1 LASTPIN (-6225 2550) BN 5
J 0
(-6277 2558);
DISPLAY 0.489362 (-6277 2558);
PAINT MONO (-6277 2558);
FORCEPROP 2 LAST CDS_LIB standard
J 0
(-6275 2550);
DISPLAY INVISIBLE (-6275 2550);
FORCEPROP 1 LAST BODY_TYPE PLUMBING
J 0
(-6275 2500);
DISPLAY 0.574468 (-6275 2500);
PAINT GREEN (-6275 2500);
DISPLAY INVISIBLE (-6275 2500);
FORCEPROP 1 LAST HDL_TAP TRUE
J 0
(-5950 2425);
DISPLAY 0.574468 (-5950 2425);
PAINT GREEN (-5950 2425);
DISPLAY INVISIBLE (-5950 2425);
FORCEPROP 1 LAST PATH I302
J 0
(-6277 2550);
DISPLAY 0.872340 (-6277 2550);
PAINT GREEN (-6277 2550);
DISPLAY INVISIBLE (-6277 2550);
FORCEADD OFFPAGE..2
(-2725 2675);
FORCEPROP 2 LAST $XR0 64 
J 0
(-2536 2675);
DISPLAY 0.638298 (-2536 2675);
PAINT MONO (-2536 2675);
FORCEPROP 2 LAST CDS_LIB standard
J 0
(-2725 2675);
DISPLAY INVISIBLE (-2725 2675);
FORCEPROP 1 LAST OFFPAGE TRUE
J 0
(-2400 2550);
DISPLAY 0.872340 (-2400 2550);
PAINT GREEN (-2400 2550);
DISPLAY INVISIBLE (-2400 2550);
FORCEPROP 1 LAST COMMENT_BODY TRUE
J 0
(-2770 2580);
DISPLAY 0.872340 (-2770 2580);
PAINT GREEN (-2770 2580);
DISPLAY INVISIBLE (-2770 2580);
FORCEPROP 2 LAST PATH I304
J 0
(-2550 2750);
DISPLAY 1.021277 (-2550 2750);
DISPLAY INVISIBLE (-2550 2750);
FORCEADD OFFPAGE..2
(-2725 2625);
FORCEPROP 2 LAST $XR0 64 
J 0
(-2536 2625);
DISPLAY 0.638298 (-2536 2625);
PAINT MONO (-2536 2625);
FORCEPROP 2 LAST PATH I315
J 0
(-2550 2700);
DISPLAY 1.021277 (-2550 2700);
DISPLAY INVISIBLE (-2550 2700);
FORCEPROP 1 LAST COMMENT_BODY TRUE
J 0
(-2770 2530);
DISPLAY 0.872340 (-2770 2530);
PAINT GREEN (-2770 2530);
DISPLAY INVISIBLE (-2770 2530);
FORCEPROP 1 LAST OFFPAGE TRUE
J 0
(-2400 2500);
DISPLAY 0.872340 (-2400 2500);
PAINT GREEN (-2400 2500);
DISPLAY INVISIBLE (-2400 2500);
FORCEPROP 2 LAST CDS_LIB standard
J 0
(-2725 2625);
DISPLAY INVISIBLE (-2725 2625);
FORCEADD TAP..6
R 2
(-3700 2600);
FORCEPROP 3 LASTPIN (-3750 2600) SIG_NAME P5E_CPU0_P3_TX_DN<4>
J 0
(-3740 2610);
DISPLAY 0.659574 (-3740 2610);
PAINT MONO (-3740 2610);
DISPLAY INVISIBLE (-3740 2610);
FORCEPROP 1 LASTPIN (-3750 2600) BN 4
J 2
(-3698 2608);
DISPLAY 0.489362 (-3698 2608);
PAINT MONO (-3698 2608);
FORCEPROP 2 LAST BOM_COST IO_SLOT
J 0
(-4200 2700);
DISPLAY 0.829787 (-4200 2700);
DISPLAY INVISIBLE (-4200 2700);
FORCEPROP 2 LAST CDS_LIB standard
J 0
(-3700 2600);
DISPLAY INVISIBLE (-3700 2600);
FORCEPROP 1 LAST BODY_TYPE PLUMBING
J 2
(-3700 2550);
DISPLAY 0.702128 (-3700 2550);
PAINT GREEN (-3700 2550);
DISPLAY INVISIBLE (-3700 2550);
FORCEPROP 1 LAST HDL_TAP TRUE
J 2
(-4025 2475);
DISPLAY 0.702128 (-4025 2475);
PAINT GREEN (-4025 2475);
DISPLAY INVISIBLE (-4025 2475);
FORCEPROP 1 LAST PATH I316
J 2
(-3698 2600);
DISPLAY 0.872340 (-3698 2600);
PAINT GREEN (-3698 2600);
DISPLAY INVISIBLE (-3698 2600);
FORCEPROP 2 LAST ROOM RISER1
J 0
(-4200 2650);
DISPLAY 0.829787 (-4200 2650);
PAINT RED (-4200 2650);
DISPLAY INVISIBLE (-4200 2650);
FORCEADD TAP..6
R 2
(-3700 2500);
FORCEPROP 3 LASTPIN (-3750 2500) SIG_NAME P5E_CPU0_P3_TX_DN<5>
J 0
(-3740 2510);
DISPLAY 0.659574 (-3740 2510);
PAINT MONO (-3740 2510);
DISPLAY INVISIBLE (-3740 2510);
FORCEPROP 1 LASTPIN (-3750 2500) BN 5
J 2
(-3698 2508);
DISPLAY 0.489362 (-3698 2508);
PAINT MONO (-3698 2508);
FORCEPROP 2 LAST BOM_COST IO_SLOT
J 0
(-4200 2600);
DISPLAY 0.829787 (-4200 2600);
DISPLAY INVISIBLE (-4200 2600);
FORCEPROP 2 LAST CDS_LIB standard
J 0
(-3700 2500);
DISPLAY INVISIBLE (-3700 2500);
FORCEPROP 1 LAST BODY_TYPE PLUMBING
J 2
(-3700 2450);
DISPLAY 0.702128 (-3700 2450);
PAINT GREEN (-3700 2450);
DISPLAY INVISIBLE (-3700 2450);
FORCEPROP 1 LAST HDL_TAP TRUE
J 2
(-4025 2375);
DISPLAY 0.702128 (-4025 2375);
PAINT GREEN (-4025 2375);
DISPLAY INVISIBLE (-4025 2375);
FORCEPROP 1 LAST PATH I317
J 2
(-3698 2500);
DISPLAY 0.872340 (-3698 2500);
PAINT GREEN (-3698 2500);
DISPLAY INVISIBLE (-3698 2500);
FORCEPROP 2 LAST ROOM RISER1
J 0
(-4200 2550);
DISPLAY 0.829787 (-4200 2550);
PAINT RED (-4200 2550);
DISPLAY INVISIBLE (-4200 2550);
FORCEADD TAP..6
R 2
(-3700 2400);
FORCEPROP 3 LASTPIN (-3750 2400) SIG_NAME P5E_CPU0_P3_TX_DN<6>
J 0
(-3740 2410);
DISPLAY 0.659574 (-3740 2410);
PAINT MONO (-3740 2410);
DISPLAY INVISIBLE (-3740 2410);
FORCEPROP 1 LASTPIN (-3750 2400) BN 6
J 2
(-3698 2408);
DISPLAY 0.489362 (-3698 2408);
PAINT MONO (-3698 2408);
FORCEPROP 2 LAST BOM_COST IO_SLOT
J 0
(-4200 2500);
DISPLAY 0.829787 (-4200 2500);
DISPLAY INVISIBLE (-4200 2500);
FORCEPROP 2 LAST CDS_LIB standard
J 0
(-3700 2400);
DISPLAY INVISIBLE (-3700 2400);
FORCEPROP 1 LAST BODY_TYPE PLUMBING
J 2
(-3700 2350);
DISPLAY 0.702128 (-3700 2350);
PAINT GREEN (-3700 2350);
DISPLAY INVISIBLE (-3700 2350);
FORCEPROP 1 LAST HDL_TAP TRUE
J 2
(-4025 2275);
DISPLAY 0.702128 (-4025 2275);
PAINT GREEN (-4025 2275);
DISPLAY INVISIBLE (-4025 2275);
FORCEPROP 1 LAST PATH I318
J 2
(-3698 2400);
DISPLAY 0.872340 (-3698 2400);
PAINT GREEN (-3698 2400);
DISPLAY INVISIBLE (-3698 2400);
FORCEPROP 2 LAST ROOM RISER1
J 0
(-4200 2450);
DISPLAY 0.829787 (-4200 2450);
PAINT RED (-4200 2450);
DISPLAY INVISIBLE (-4200 2450);
FORCEADD TAP..6
R 2
(-3700 2300);
FORCEPROP 3 LASTPIN (-3750 2300) SIG_NAME P5E_CPU0_P3_TX_DN<7>
J 0
(-3740 2310);
DISPLAY 0.659574 (-3740 2310);
PAINT MONO (-3740 2310);
DISPLAY INVISIBLE (-3740 2310);
FORCEPROP 1 LASTPIN (-3750 2300) BN 7
J 2
(-3698 2308);
DISPLAY 0.489362 (-3698 2308);
PAINT MONO (-3698 2308);
FORCEPROP 2 LAST BOM_COST IO_SLOT
J 0
(-4200 2400);
DISPLAY 0.829787 (-4200 2400);
DISPLAY INVISIBLE (-4200 2400);
FORCEPROP 2 LAST CDS_LIB standard
J 0
(-3700 2300);
DISPLAY INVISIBLE (-3700 2300);
FORCEPROP 1 LAST BODY_TYPE PLUMBING
J 2
(-3700 2250);
DISPLAY 0.702128 (-3700 2250);
PAINT GREEN (-3700 2250);
DISPLAY INVISIBLE (-3700 2250);
FORCEPROP 1 LAST HDL_TAP TRUE
J 2
(-4025 2175);
DISPLAY 0.702128 (-4025 2175);
PAINT GREEN (-4025 2175);
DISPLAY INVISIBLE (-4025 2175);
FORCEPROP 1 LAST PATH I319
J 2
(-3698 2300);
DISPLAY 0.872340 (-3698 2300);
PAINT GREEN (-3698 2300);
DISPLAY INVISIBLE (-3698 2300);
FORCEPROP 2 LAST ROOM RISER1
J 0
(-4200 2350);
DISPLAY 0.829787 (-4200 2350);
PAINT RED (-4200 2350);
DISPLAY INVISIBLE (-4200 2350);
FORCEADD TAP..6
(-6425 2600);
FORCEPROP 3 LASTPIN (-6375 2600) SIG_NAME P5E_CPU0_P3_RX_DN<4>
J 0
(-6365 2610);
DISPLAY 0.659574 (-6365 2610);
PAINT MONO (-6365 2610);
DISPLAY INVISIBLE (-6365 2610);
FORCEPROP 1 LASTPIN (-6375 2600) BN 4
J 0
(-6427 2608);
DISPLAY 0.489362 (-6427 2608);
PAINT MONO (-6427 2608);
FORCEPROP 2 LAST CDS_LIB standard
J 0
(-6425 2600);
DISPLAY INVISIBLE (-6425 2600);
FORCEPROP 1 LAST BODY_TYPE PLUMBING
J 0
(-6425 2550);
DISPLAY 0.574468 (-6425 2550);
PAINT GREEN (-6425 2550);
DISPLAY INVISIBLE (-6425 2550);
FORCEPROP 1 LAST HDL_TAP TRUE
J 0
(-6100 2475);
DISPLAY 0.574468 (-6100 2475);
PAINT GREEN (-6100 2475);
DISPLAY INVISIBLE (-6100 2475);
FORCEPROP 1 LAST PATH I320
J 0
(-6427 2600);
DISPLAY 0.872340 (-6427 2600);
PAINT GREEN (-6427 2600);
DISPLAY INVISIBLE (-6427 2600);
FORCEADD TAP..6
(-6425 2400);
FORCEPROP 3 LASTPIN (-6375 2400) SIG_NAME P5E_CPU0_P3_RX_DN<6>
J 0
(-6365 2410);
DISPLAY 0.659574 (-6365 2410);
PAINT MONO (-6365 2410);
DISPLAY INVISIBLE (-6365 2410);
FORCEPROP 1 LASTPIN (-6375 2400) BN 6
J 0
(-6427 2408);
DISPLAY 0.489362 (-6427 2408);
PAINT MONO (-6427 2408);
FORCEPROP 2 LAST CDS_LIB standard
J 0
(-6425 2400);
DISPLAY INVISIBLE (-6425 2400);
FORCEPROP 1 LAST BODY_TYPE PLUMBING
J 0
(-6425 2350);
DISPLAY 0.574468 (-6425 2350);
PAINT GREEN (-6425 2350);
DISPLAY INVISIBLE (-6425 2350);
FORCEPROP 1 LAST HDL_TAP TRUE
J 0
(-6100 2275);
DISPLAY 0.574468 (-6100 2275);
PAINT GREEN (-6100 2275);
DISPLAY INVISIBLE (-6100 2275);
FORCEPROP 1 LAST PATH I321
J 0
(-6427 2400);
DISPLAY 0.872340 (-6427 2400);
PAINT GREEN (-6427 2400);
DISPLAY INVISIBLE (-6427 2400);
FORCEADD TAP..6
(-6425 2500);
FORCEPROP 3 LASTPIN (-6375 2500) SIG_NAME P5E_CPU0_P3_RX_DN<5>
J 0
(-6365 2510);
DISPLAY 0.659574 (-6365 2510);
PAINT MONO (-6365 2510);
DISPLAY INVISIBLE (-6365 2510);
FORCEPROP 1 LASTPIN (-6375 2500) BN 5
J 0
(-6427 2508);
DISPLAY 0.489362 (-6427 2508);
PAINT MONO (-6427 2508);
FORCEPROP 2 LAST CDS_LIB standard
J 0
(-6425 2500);
DISPLAY INVISIBLE (-6425 2500);
FORCEPROP 1 LAST BODY_TYPE PLUMBING
J 0
(-6425 2450);
DISPLAY 0.574468 (-6425 2450);
PAINT GREEN (-6425 2450);
DISPLAY INVISIBLE (-6425 2450);
FORCEPROP 1 LAST HDL_TAP TRUE
J 0
(-6100 2375);
DISPLAY 0.574468 (-6100 2375);
PAINT GREEN (-6100 2375);
DISPLAY INVISIBLE (-6100 2375);
FORCEPROP 1 LAST PATH I322
J 0
(-6427 2500);
DISPLAY 0.872340 (-6427 2500);
PAINT GREEN (-6427 2500);
DISPLAY INVISIBLE (-6427 2500);
FORCEADD TAP..6
(-6425 2300);
FORCEPROP 3 LASTPIN (-6375 2300) SIG_NAME P5E_CPU0_P3_RX_DN<7>
J 0
(-6365 2310);
DISPLAY 0.659574 (-6365 2310);
PAINT MONO (-6365 2310);
DISPLAY INVISIBLE (-6365 2310);
FORCEPROP 1 LASTPIN (-6375 2300) BN 7
J 0
(-6427 2308);
DISPLAY 0.489362 (-6427 2308);
PAINT MONO (-6427 2308);
FORCEPROP 2 LAST CDS_LIB standard
J 0
(-6425 2300);
DISPLAY INVISIBLE (-6425 2300);
FORCEPROP 1 LAST BODY_TYPE PLUMBING
J 0
(-6425 2250);
DISPLAY 0.574468 (-6425 2250);
PAINT GREEN (-6425 2250);
DISPLAY INVISIBLE (-6425 2250);
FORCEPROP 1 LAST HDL_TAP TRUE
J 0
(-6100 2175);
DISPLAY 0.574468 (-6100 2175);
PAINT GREEN (-6100 2175);
DISPLAY INVISIBLE (-6100 2175);
FORCEPROP 1 LAST PATH I323
J 0
(-6427 2300);
DISPLAY 0.872340 (-6427 2300);
PAINT GREEN (-6427 2300);
DISPLAY INVISIBLE (-6427 2300);
FORCEADD OFFPAGE..1
(-7375 2625);
FORCEPROP 2 LASTPIN (-7325 2625) SIG_NAME P5E_CPU0_P3_RX_DN<7:4>
J 0
(-7350 2635);
DISPLAY 0.489362 (-7350 2635);
FORCEPROP 2 LAST $XR0 117 
J 0
(-7627 2625);
DISPLAY 0.638298 (-7627 2625);
PAINT MONO (-7627 2625);
FORCEPROP 2 LAST PATH I324
J 0
(-7325 2700);
DISPLAY 1.021277 (-7325 2700);
DISPLAY INVISIBLE (-7325 2700);
FORCEPROP 1 LAST COMMENT_BODY TRUE
J 0
(-7250 2525);
DISPLAY 0.872340 (-7250 2525);
PAINT GREEN (-7250 2525);
DISPLAY INVISIBLE (-7250 2525);
FORCEPROP 1 LAST OFFPAGE TRUE
J 0
(-7050 2500);
DISPLAY 0.872340 (-7050 2500);
PAINT GREEN (-7050 2500);
DISPLAY INVISIBLE (-7050 2500);
FORCEPROP 2 LAST CDS_LIB standard
J 0
(-7375 2625);
DISPLAY INVISIBLE (-7375 2625);
FORCEADD TAP..6
(-6300 5875);
FORCEPROP 3 LASTPIN (-6250 5875) SIG_NAME P5E_CPU0_P2_RX_DP<0>
J 0
(-6240 5885);
DISPLAY 0.659574 (-6240 5885);
PAINT MONO (-6240 5885);
DISPLAY INVISIBLE (-6240 5885);
FORCEPROP 1 LASTPIN (-6250 5875) BN 0
J 0
(-6302 5883);
DISPLAY 0.489362 (-6302 5883);
PAINT MONO (-6302 5883);
FORCEPROP 2 LAST CDS_LIB mstr_standard
J 0
(-6300 5875);
DISPLAY INVISIBLE (-6300 5875);
FORCEPROP 1 LAST BODY_TYPE PLUMBING
J 0
(-6300 5825);
DISPLAY 0.574468 (-6300 5825);
PAINT GREEN (-6300 5825);
DISPLAY INVISIBLE (-6300 5825);
FORCEPROP 1 LAST HDL_TAP TRUE
J 0
(-5975 5750);
DISPLAY 0.574468 (-5975 5750);
PAINT GREEN (-5975 5750);
DISPLAY INVISIBLE (-5975 5750);
FORCEPROP 1 LAST PATH I325
J 0
(-6302 5875);
DISPLAY 0.872340 (-6302 5875);
PAINT GREEN (-6302 5875);
DISPLAY INVISIBLE (-6302 5875);
FORCEADD TAP..6
(-6300 5675);
FORCEPROP 3 LASTPIN (-6250 5675) SIG_NAME P5E_CPU0_P2_RX_DP<2>
J 0
(-6240 5685);
DISPLAY 0.659574 (-6240 5685);
PAINT MONO (-6240 5685);
DISPLAY INVISIBLE (-6240 5685);
FORCEPROP 1 LASTPIN (-6250 5675) BN 2
J 0
(-6302 5683);
DISPLAY 0.489362 (-6302 5683);
PAINT MONO (-6302 5683);
FORCEPROP 2 LAST CDS_LIB mstr_standard
J 0
(-6300 5675);
DISPLAY INVISIBLE (-6300 5675);
FORCEPROP 1 LAST BODY_TYPE PLUMBING
J 0
(-6300 5625);
DISPLAY 0.574468 (-6300 5625);
PAINT GREEN (-6300 5625);
DISPLAY INVISIBLE (-6300 5625);
FORCEPROP 1 LAST HDL_TAP TRUE
J 0
(-5975 5550);
DISPLAY 0.574468 (-5975 5550);
PAINT GREEN (-5975 5550);
DISPLAY INVISIBLE (-5975 5550);
FORCEPROP 1 LAST PATH I326
J 0
(-6302 5675);
DISPLAY 0.872340 (-6302 5675);
PAINT GREEN (-6302 5675);
DISPLAY INVISIBLE (-6302 5675);
FORCEADD TAP..6
(-6300 5775);
FORCEPROP 3 LASTPIN (-6250 5775) SIG_NAME P5E_CPU0_P2_RX_DP<1>
J 0
(-6240 5785);
DISPLAY 0.659574 (-6240 5785);
PAINT MONO (-6240 5785);
DISPLAY INVISIBLE (-6240 5785);
FORCEPROP 1 LASTPIN (-6250 5775) BN 1
J 0
(-6302 5783);
DISPLAY 0.489362 (-6302 5783);
PAINT MONO (-6302 5783);
FORCEPROP 2 LAST CDS_LIB mstr_standard
J 0
(-6300 5775);
DISPLAY INVISIBLE (-6300 5775);
FORCEPROP 1 LAST BODY_TYPE PLUMBING
J 0
(-6300 5725);
DISPLAY 0.574468 (-6300 5725);
PAINT GREEN (-6300 5725);
DISPLAY INVISIBLE (-6300 5725);
FORCEPROP 1 LAST HDL_TAP TRUE
J 0
(-5975 5650);
DISPLAY 0.574468 (-5975 5650);
PAINT GREEN (-5975 5650);
DISPLAY INVISIBLE (-5975 5650);
FORCEPROP 1 LAST PATH I327
J 0
(-6302 5775);
DISPLAY 0.872340 (-6302 5775);
PAINT GREEN (-6302 5775);
DISPLAY INVISIBLE (-6302 5775);
FORCEADD TAP..6
(-6450 5825);
FORCEPROP 3 LASTPIN (-6400 5825) SIG_NAME P5E_CPU0_P2_RX_DN<0>
J 0
(-6390 5835);
DISPLAY 0.659574 (-6390 5835);
PAINT MONO (-6390 5835);
DISPLAY INVISIBLE (-6390 5835);
FORCEPROP 1 LASTPIN (-6400 5825) BN 0
J 0
(-6452 5833);
DISPLAY 0.489362 (-6452 5833);
PAINT MONO (-6452 5833);
FORCEPROP 2 LAST CDS_LIB mstr_standard
J 0
(-6450 5825);
DISPLAY INVISIBLE (-6450 5825);
FORCEPROP 1 LAST BODY_TYPE PLUMBING
J 0
(-6450 5775);
DISPLAY 0.574468 (-6450 5775);
PAINT GREEN (-6450 5775);
DISPLAY INVISIBLE (-6450 5775);
FORCEPROP 1 LAST HDL_TAP TRUE
J 0
(-6125 5700);
DISPLAY 0.574468 (-6125 5700);
PAINT GREEN (-6125 5700);
DISPLAY INVISIBLE (-6125 5700);
FORCEPROP 1 LAST PATH I328
J 0
(-6452 5825);
DISPLAY 0.872340 (-6452 5825);
PAINT GREEN (-6452 5825);
DISPLAY INVISIBLE (-6452 5825);
FORCEADD TAP..6
(-6450 5725);
FORCEPROP 3 LASTPIN (-6400 5725) SIG_NAME P5E_CPU0_P2_RX_DN<1>
J 0
(-6390 5735);
DISPLAY 0.659574 (-6390 5735);
PAINT MONO (-6390 5735);
DISPLAY INVISIBLE (-6390 5735);
FORCEPROP 1 LASTPIN (-6400 5725) BN 1
J 0
(-6452 5733);
DISPLAY 0.489362 (-6452 5733);
PAINT MONO (-6452 5733);
FORCEPROP 2 LAST CDS_LIB mstr_standard
J 0
(-6450 5725);
DISPLAY INVISIBLE (-6450 5725);
FORCEPROP 1 LAST BODY_TYPE PLUMBING
J 0
(-6450 5675);
DISPLAY 0.574468 (-6450 5675);
PAINT GREEN (-6450 5675);
DISPLAY INVISIBLE (-6450 5675);
FORCEPROP 1 LAST HDL_TAP TRUE
J 0
(-6125 5600);
DISPLAY 0.574468 (-6125 5600);
PAINT GREEN (-6125 5600);
DISPLAY INVISIBLE (-6125 5600);
FORCEPROP 1 LAST PATH I329
J 0
(-6452 5725);
DISPLAY 0.872340 (-6452 5725);
PAINT GREEN (-6452 5725);
DISPLAY INVISIBLE (-6452 5725);
FORCEADD TAP..6
(-6300 5575);
FORCEPROP 3 LASTPIN (-6250 5575) SIG_NAME P5E_CPU0_P2_RX_DP<3>
J 0
(-6240 5585);
DISPLAY 0.659574 (-6240 5585);
PAINT MONO (-6240 5585);
DISPLAY INVISIBLE (-6240 5585);
FORCEPROP 1 LASTPIN (-6250 5575) BN 3
J 0
(-6302 5583);
DISPLAY 0.489362 (-6302 5583);
PAINT MONO (-6302 5583);
FORCEPROP 2 LAST CDS_LIB standard
J 0
(-6300 5575);
DISPLAY INVISIBLE (-6300 5575);
FORCEPROP 1 LAST BODY_TYPE PLUMBING
J 0
(-6300 5525);
DISPLAY 0.574468 (-6300 5525);
PAINT GREEN (-6300 5525);
DISPLAY INVISIBLE (-6300 5525);
FORCEPROP 1 LAST HDL_TAP TRUE
J 0
(-5975 5450);
DISPLAY 0.574468 (-5975 5450);
PAINT GREEN (-5975 5450);
DISPLAY INVISIBLE (-5975 5450);
FORCEPROP 1 LAST PATH I330
J 0
(-6302 5575);
DISPLAY 0.872340 (-6302 5575);
PAINT GREEN (-6302 5575);
DISPLAY INVISIBLE (-6302 5575);
FORCEADD TAP..6
(-6300 5475);
FORCEPROP 3 LASTPIN (-6250 5475) SIG_NAME P5E_CPU0_P2_RX_DP<4>
J 0
(-6240 5485);
DISPLAY 0.659574 (-6240 5485);
PAINT MONO (-6240 5485);
DISPLAY INVISIBLE (-6240 5485);
FORCEPROP 1 LASTPIN (-6250 5475) BN 4
J 0
(-6302 5483);
DISPLAY 0.489362 (-6302 5483);
PAINT MONO (-6302 5483);
FORCEPROP 2 LAST CDS_LIB standard
J 0
(-6300 5475);
DISPLAY INVISIBLE (-6300 5475);
FORCEPROP 1 LAST BODY_TYPE PLUMBING
J 0
(-6300 5425);
DISPLAY 0.574468 (-6300 5425);
PAINT GREEN (-6300 5425);
DISPLAY INVISIBLE (-6300 5425);
FORCEPROP 1 LAST HDL_TAP TRUE
J 0
(-5975 5350);
DISPLAY 0.574468 (-5975 5350);
PAINT GREEN (-5975 5350);
DISPLAY INVISIBLE (-5975 5350);
FORCEPROP 1 LAST PATH I331
J 0
(-6302 5475);
DISPLAY 0.872340 (-6302 5475);
PAINT GREEN (-6302 5475);
DISPLAY INVISIBLE (-6302 5475);
FORCEADD TAP..6
(-6300 5275);
FORCEPROP 3 LASTPIN (-6250 5275) SIG_NAME P5E_CPU0_P2_RX_DP<6>
J 0
(-6240 5285);
DISPLAY 0.659574 (-6240 5285);
PAINT MONO (-6240 5285);
DISPLAY INVISIBLE (-6240 5285);
FORCEPROP 1 LASTPIN (-6250 5275) BN 6
J 0
(-6302 5283);
DISPLAY 0.489362 (-6302 5283);
PAINT MONO (-6302 5283);
FORCEPROP 2 LAST CDS_LIB standard
J 0
(-6300 5275);
DISPLAY INVISIBLE (-6300 5275);
FORCEPROP 1 LAST BODY_TYPE PLUMBING
J 0
(-6300 5225);
DISPLAY 0.574468 (-6300 5225);
PAINT GREEN (-6300 5225);
DISPLAY INVISIBLE (-6300 5225);
FORCEPROP 1 LAST HDL_TAP TRUE
J 0
(-5975 5150);
DISPLAY 0.574468 (-5975 5150);
PAINT GREEN (-5975 5150);
DISPLAY INVISIBLE (-5975 5150);
FORCEPROP 1 LAST PATH I332
J 0
(-6302 5275);
DISPLAY 0.872340 (-6302 5275);
PAINT GREEN (-6302 5275);
DISPLAY INVISIBLE (-6302 5275);
FORCEADD TAP..6
(-6300 5375);
FORCEPROP 3 LASTPIN (-6250 5375) SIG_NAME P5E_CPU0_P2_RX_DP<5>
J 0
(-6240 5385);
DISPLAY 0.659574 (-6240 5385);
PAINT MONO (-6240 5385);
DISPLAY INVISIBLE (-6240 5385);
FORCEPROP 1 LASTPIN (-6250 5375) BN 5
J 0
(-6302 5383);
DISPLAY 0.489362 (-6302 5383);
PAINT MONO (-6302 5383);
FORCEPROP 2 LAST CDS_LIB standard
J 0
(-6300 5375);
DISPLAY INVISIBLE (-6300 5375);
FORCEPROP 1 LAST BODY_TYPE PLUMBING
J 0
(-6300 5325);
DISPLAY 0.574468 (-6300 5325);
PAINT GREEN (-6300 5325);
DISPLAY INVISIBLE (-6300 5325);
FORCEPROP 1 LAST HDL_TAP TRUE
J 0
(-5975 5250);
DISPLAY 0.574468 (-5975 5250);
PAINT GREEN (-5975 5250);
DISPLAY INVISIBLE (-5975 5250);
FORCEPROP 1 LAST PATH I333
J 0
(-6302 5375);
DISPLAY 0.872340 (-6302 5375);
PAINT GREEN (-6302 5375);
DISPLAY INVISIBLE (-6302 5375);
FORCEADD TAP..6
(-6300 5175);
FORCEPROP 3 LASTPIN (-6250 5175) SIG_NAME P5E_CPU0_P2_RX_DP<7>
J 0
(-6240 5185);
DISPLAY 0.659574 (-6240 5185);
PAINT MONO (-6240 5185);
DISPLAY INVISIBLE (-6240 5185);
FORCEPROP 1 LASTPIN (-6250 5175) BN 7
J 0
(-6302 5183);
DISPLAY 0.489362 (-6302 5183);
PAINT MONO (-6302 5183);
FORCEPROP 2 LAST CDS_LIB standard
J 0
(-6300 5175);
DISPLAY INVISIBLE (-6300 5175);
FORCEPROP 1 LAST BODY_TYPE PLUMBING
J 0
(-6300 5125);
DISPLAY 0.574468 (-6300 5125);
PAINT GREEN (-6300 5125);
DISPLAY INVISIBLE (-6300 5125);
FORCEPROP 1 LAST HDL_TAP TRUE
J 0
(-5975 5050);
DISPLAY 0.574468 (-5975 5050);
PAINT GREEN (-5975 5050);
DISPLAY INVISIBLE (-5975 5050);
FORCEPROP 1 LAST PATH I334
J 0
(-6302 5175);
DISPLAY 0.872340 (-6302 5175);
PAINT GREEN (-6302 5175);
DISPLAY INVISIBLE (-6302 5175);
FORCEADD TAP..6
(-6450 5525);
FORCEPROP 3 LASTPIN (-6400 5525) SIG_NAME P5E_CPU0_P2_RX_DN<3>
J 0
(-6390 5535);
DISPLAY 0.659574 (-6390 5535);
PAINT MONO (-6390 5535);
DISPLAY INVISIBLE (-6390 5535);
FORCEPROP 1 LASTPIN (-6400 5525) BN 3
J 0
(-6452 5533);
DISPLAY 0.489362 (-6452 5533);
PAINT MONO (-6452 5533);
FORCEPROP 2 LAST CDS_LIB standard
J 0
(-6450 5525);
DISPLAY INVISIBLE (-6450 5525);
FORCEPROP 1 LAST BODY_TYPE PLUMBING
J 0
(-6450 5475);
DISPLAY 0.574468 (-6450 5475);
PAINT GREEN (-6450 5475);
DISPLAY INVISIBLE (-6450 5475);
FORCEPROP 1 LAST HDL_TAP TRUE
J 0
(-6125 5400);
DISPLAY 0.574468 (-6125 5400);
PAINT GREEN (-6125 5400);
DISPLAY INVISIBLE (-6125 5400);
FORCEPROP 1 LAST PATH I335
J 0
(-6452 5525);
DISPLAY 0.872340 (-6452 5525);
PAINT GREEN (-6452 5525);
DISPLAY INVISIBLE (-6452 5525);
FORCEADD TAP..6
(-6450 5425);
FORCEPROP 3 LASTPIN (-6400 5425) SIG_NAME P5E_CPU0_P2_RX_DN<4>
J 0
(-6390 5435);
DISPLAY 0.659574 (-6390 5435);
PAINT MONO (-6390 5435);
DISPLAY INVISIBLE (-6390 5435);
FORCEPROP 1 LASTPIN (-6400 5425) BN 4
J 0
(-6452 5433);
DISPLAY 0.489362 (-6452 5433);
PAINT MONO (-6452 5433);
FORCEPROP 2 LAST CDS_LIB standard
J 0
(-6450 5425);
DISPLAY INVISIBLE (-6450 5425);
FORCEPROP 1 LAST BODY_TYPE PLUMBING
J 0
(-6450 5375);
DISPLAY 0.574468 (-6450 5375);
PAINT GREEN (-6450 5375);
DISPLAY INVISIBLE (-6450 5375);
FORCEPROP 1 LAST HDL_TAP TRUE
J 0
(-6125 5300);
DISPLAY 0.574468 (-6125 5300);
PAINT GREEN (-6125 5300);
DISPLAY INVISIBLE (-6125 5300);
FORCEPROP 1 LAST PATH I336
J 0
(-6452 5425);
DISPLAY 0.872340 (-6452 5425);
PAINT GREEN (-6452 5425);
DISPLAY INVISIBLE (-6452 5425);
FORCEADD TAP..6
(-6450 5625);
FORCEPROP 3 LASTPIN (-6400 5625) SIG_NAME P5E_CPU0_P2_RX_DN<2>
J 0
(-6390 5635);
DISPLAY 0.659574 (-6390 5635);
PAINT MONO (-6390 5635);
DISPLAY INVISIBLE (-6390 5635);
FORCEPROP 1 LASTPIN (-6400 5625) BN 2
J 0
(-6452 5633);
DISPLAY 0.489362 (-6452 5633);
PAINT MONO (-6452 5633);
FORCEPROP 2 LAST CDS_LIB standard
J 0
(-6450 5625);
DISPLAY INVISIBLE (-6450 5625);
FORCEPROP 1 LAST BODY_TYPE PLUMBING
J 0
(-6450 5575);
DISPLAY 0.574468 (-6450 5575);
PAINT GREEN (-6450 5575);
DISPLAY INVISIBLE (-6450 5575);
FORCEPROP 1 LAST HDL_TAP TRUE
J 0
(-6125 5500);
DISPLAY 0.574468 (-6125 5500);
PAINT GREEN (-6125 5500);
DISPLAY INVISIBLE (-6125 5500);
FORCEPROP 1 LAST PATH I337
J 0
(-6452 5625);
DISPLAY 0.872340 (-6452 5625);
PAINT GREEN (-6452 5625);
DISPLAY INVISIBLE (-6452 5625);
FORCEADD TAP..6
(-6450 5325);
FORCEPROP 3 LASTPIN (-6400 5325) SIG_NAME P5E_CPU0_P2_RX_DN<5>
J 0
(-6390 5335);
DISPLAY 0.659574 (-6390 5335);
PAINT MONO (-6390 5335);
DISPLAY INVISIBLE (-6390 5335);
FORCEPROP 1 LASTPIN (-6400 5325) BN 5
J 0
(-6452 5333);
DISPLAY 0.489362 (-6452 5333);
PAINT MONO (-6452 5333);
FORCEPROP 2 LAST CDS_LIB standard
J 0
(-6450 5325);
DISPLAY INVISIBLE (-6450 5325);
FORCEPROP 1 LAST BODY_TYPE PLUMBING
J 0
(-6450 5275);
DISPLAY 0.574468 (-6450 5275);
PAINT GREEN (-6450 5275);
DISPLAY INVISIBLE (-6450 5275);
FORCEPROP 1 LAST HDL_TAP TRUE
J 0
(-6125 5200);
DISPLAY 0.574468 (-6125 5200);
PAINT GREEN (-6125 5200);
DISPLAY INVISIBLE (-6125 5200);
FORCEPROP 1 LAST PATH I338
J 0
(-6452 5325);
DISPLAY 0.872340 (-6452 5325);
PAINT GREEN (-6452 5325);
DISPLAY INVISIBLE (-6452 5325);
FORCEADD TAP..6
(-6450 5225);
FORCEPROP 3 LASTPIN (-6400 5225) SIG_NAME P5E_CPU0_P2_RX_DN<6>
J 0
(-6390 5235);
DISPLAY 0.659574 (-6390 5235);
PAINT MONO (-6390 5235);
DISPLAY INVISIBLE (-6390 5235);
FORCEPROP 1 LASTPIN (-6400 5225) BN 6
J 0
(-6452 5233);
DISPLAY 0.489362 (-6452 5233);
PAINT MONO (-6452 5233);
FORCEPROP 2 LAST CDS_LIB standard
J 0
(-6450 5225);
DISPLAY INVISIBLE (-6450 5225);
FORCEPROP 1 LAST BODY_TYPE PLUMBING
J 0
(-6450 5175);
DISPLAY 0.574468 (-6450 5175);
PAINT GREEN (-6450 5175);
DISPLAY INVISIBLE (-6450 5175);
FORCEPROP 1 LAST HDL_TAP TRUE
J 0
(-6125 5100);
DISPLAY 0.574468 (-6125 5100);
PAINT GREEN (-6125 5100);
DISPLAY INVISIBLE (-6125 5100);
FORCEPROP 1 LAST PATH I339
J 0
(-6452 5225);
DISPLAY 0.872340 (-6452 5225);
PAINT GREEN (-6452 5225);
DISPLAY INVISIBLE (-6452 5225);
FORCEADD TAP..6
(-6300 5075);
FORCEPROP 3 LASTPIN (-6250 5075) SIG_NAME P5E_CPU0_P2_RX_DP<8>
J 0
(-6240 5085);
DISPLAY 0.659574 (-6240 5085);
PAINT MONO (-6240 5085);
DISPLAY INVISIBLE (-6240 5085);
FORCEPROP 1 LASTPIN (-6250 5075) BN 8
J 0
(-6302 5083);
DISPLAY 0.489362 (-6302 5083);
PAINT MONO (-6302 5083);
FORCEPROP 2 LAST CDS_LIB standard
J 0
(-6300 5075);
DISPLAY INVISIBLE (-6300 5075);
FORCEPROP 1 LAST BODY_TYPE PLUMBING
J 0
(-6300 5025);
DISPLAY 0.574468 (-6300 5025);
PAINT GREEN (-6300 5025);
DISPLAY INVISIBLE (-6300 5025);
FORCEPROP 1 LAST HDL_TAP TRUE
J 0
(-5975 4950);
DISPLAY 0.574468 (-5975 4950);
PAINT GREEN (-5975 4950);
DISPLAY INVISIBLE (-5975 4950);
FORCEPROP 1 LAST PATH I340
J 0
(-6302 5075);
DISPLAY 0.872340 (-6302 5075);
PAINT GREEN (-6302 5075);
DISPLAY INVISIBLE (-6302 5075);
FORCEADD TAP..6
(-6300 4975);
FORCEPROP 3 LASTPIN (-6250 4975) SIG_NAME P5E_CPU0_P2_RX_DP<9>
J 0
(-6240 4985);
DISPLAY 0.659574 (-6240 4985);
PAINT MONO (-6240 4985);
DISPLAY INVISIBLE (-6240 4985);
FORCEPROP 1 LASTPIN (-6250 4975) BN 9
J 0
(-6302 4983);
DISPLAY 0.489362 (-6302 4983);
PAINT MONO (-6302 4983);
FORCEPROP 2 LAST CDS_LIB standard
J 0
(-6300 4975);
DISPLAY INVISIBLE (-6300 4975);
FORCEPROP 1 LAST BODY_TYPE PLUMBING
J 0
(-6300 4925);
DISPLAY 0.574468 (-6300 4925);
PAINT GREEN (-6300 4925);
DISPLAY INVISIBLE (-6300 4925);
FORCEPROP 1 LAST HDL_TAP TRUE
J 0
(-5975 4850);
DISPLAY 0.574468 (-5975 4850);
PAINT GREEN (-5975 4850);
DISPLAY INVISIBLE (-5975 4850);
FORCEPROP 1 LAST PATH I341
J 0
(-6302 4975);
DISPLAY 0.872340 (-6302 4975);
PAINT GREEN (-6302 4975);
DISPLAY INVISIBLE (-6302 4975);
FORCEADD TAP..6
(-6300 4875);
FORCEPROP 3 LASTPIN (-6250 4875) SIG_NAME P5E_CPU0_P2_RX_DP<10>
J 0
(-6240 4885);
DISPLAY 0.659574 (-6240 4885);
PAINT MONO (-6240 4885);
DISPLAY INVISIBLE (-6240 4885);
FORCEPROP 1 LASTPIN (-6250 4875) BN 10
J 0
(-6302 4883);
DISPLAY 0.489362 (-6302 4883);
PAINT MONO (-6302 4883);
FORCEPROP 2 LAST CDS_LIB standard
J 0
(-6300 4875);
DISPLAY INVISIBLE (-6300 4875);
FORCEPROP 1 LAST BODY_TYPE PLUMBING
J 0
(-6300 4825);
DISPLAY 0.574468 (-6300 4825);
PAINT GREEN (-6300 4825);
DISPLAY INVISIBLE (-6300 4825);
FORCEPROP 1 LAST HDL_TAP TRUE
J 0
(-5975 4750);
DISPLAY 0.574468 (-5975 4750);
PAINT GREEN (-5975 4750);
DISPLAY INVISIBLE (-5975 4750);
FORCEPROP 1 LAST PATH I342
J 0
(-6302 4875);
DISPLAY 0.872340 (-6302 4875);
PAINT GREEN (-6302 4875);
DISPLAY INVISIBLE (-6302 4875);
FORCEADD TAP..6
(-6300 4775);
FORCEPROP 3 LASTPIN (-6250 4775) SIG_NAME P5E_CPU0_P2_RX_DP<11>
J 0
(-6240 4785);
DISPLAY 0.659574 (-6240 4785);
PAINT MONO (-6240 4785);
DISPLAY INVISIBLE (-6240 4785);
FORCEPROP 1 LASTPIN (-6250 4775) BN 11
J 0
(-6302 4783);
DISPLAY 0.489362 (-6302 4783);
PAINT MONO (-6302 4783);
FORCEPROP 2 LAST CDS_LIB standard
J 0
(-6300 4775);
DISPLAY INVISIBLE (-6300 4775);
FORCEPROP 1 LAST BODY_TYPE PLUMBING
J 0
(-6300 4725);
DISPLAY 0.574468 (-6300 4725);
PAINT GREEN (-6300 4725);
DISPLAY INVISIBLE (-6300 4725);
FORCEPROP 1 LAST HDL_TAP TRUE
J 0
(-5975 4650);
DISPLAY 0.574468 (-5975 4650);
PAINT GREEN (-5975 4650);
DISPLAY INVISIBLE (-5975 4650);
FORCEPROP 1 LAST PATH I343
J 0
(-6302 4775);
DISPLAY 0.872340 (-6302 4775);
PAINT GREEN (-6302 4775);
DISPLAY INVISIBLE (-6302 4775);
FORCEADD TAP..6
(-6300 4675);
FORCEPROP 3 LASTPIN (-6250 4675) SIG_NAME P5E_CPU0_P2_RX_DP<12>
J 0
(-6240 4685);
DISPLAY 0.659574 (-6240 4685);
PAINT MONO (-6240 4685);
DISPLAY INVISIBLE (-6240 4685);
FORCEPROP 1 LASTPIN (-6250 4675) BN 12
J 0
(-6302 4683);
DISPLAY 0.489362 (-6302 4683);
PAINT MONO (-6302 4683);
FORCEPROP 2 LAST CDS_LIB standard
J 0
(-6300 4675);
DISPLAY INVISIBLE (-6300 4675);
FORCEPROP 1 LAST BODY_TYPE PLUMBING
J 0
(-6300 4625);
DISPLAY 0.574468 (-6300 4625);
PAINT GREEN (-6300 4625);
DISPLAY INVISIBLE (-6300 4625);
FORCEPROP 1 LAST HDL_TAP TRUE
J 0
(-5975 4550);
DISPLAY 0.574468 (-5975 4550);
PAINT GREEN (-5975 4550);
DISPLAY INVISIBLE (-5975 4550);
FORCEPROP 1 LAST PATH I344
J 0
(-6302 4675);
DISPLAY 0.872340 (-6302 4675);
PAINT GREEN (-6302 4675);
DISPLAY INVISIBLE (-6302 4675);
FORCEADD TAP..6
(-6450 5125);
FORCEPROP 3 LASTPIN (-6400 5125) SIG_NAME P5E_CPU0_P2_RX_DN<7>
J 0
(-6390 5135);
DISPLAY 0.659574 (-6390 5135);
PAINT MONO (-6390 5135);
DISPLAY INVISIBLE (-6390 5135);
FORCEPROP 1 LASTPIN (-6400 5125) BN 7
J 0
(-6452 5133);
DISPLAY 0.489362 (-6452 5133);
PAINT MONO (-6452 5133);
FORCEPROP 2 LAST CDS_LIB standard
J 0
(-6450 5125);
DISPLAY INVISIBLE (-6450 5125);
FORCEPROP 1 LAST BODY_TYPE PLUMBING
J 0
(-6450 5075);
DISPLAY 0.574468 (-6450 5075);
PAINT GREEN (-6450 5075);
DISPLAY INVISIBLE (-6450 5075);
FORCEPROP 1 LAST HDL_TAP TRUE
J 0
(-6125 5000);
DISPLAY 0.574468 (-6125 5000);
PAINT GREEN (-6125 5000);
DISPLAY INVISIBLE (-6125 5000);
FORCEPROP 1 LAST PATH I345
J 0
(-6452 5125);
DISPLAY 0.872340 (-6452 5125);
PAINT GREEN (-6452 5125);
DISPLAY INVISIBLE (-6452 5125);
FORCEADD TAP..6
(-6450 4925);
FORCEPROP 3 LASTPIN (-6400 4925) SIG_NAME P5E_CPU0_P2_RX_DN<9>
J 0
(-6390 4935);
DISPLAY 0.659574 (-6390 4935);
PAINT MONO (-6390 4935);
DISPLAY INVISIBLE (-6390 4935);
FORCEPROP 1 LASTPIN (-6400 4925) BN 9
J 0
(-6452 4933);
DISPLAY 0.489362 (-6452 4933);
PAINT MONO (-6452 4933);
FORCEPROP 2 LAST CDS_LIB standard
J 0
(-6450 4925);
DISPLAY INVISIBLE (-6450 4925);
FORCEPROP 1 LAST BODY_TYPE PLUMBING
J 0
(-6450 4875);
DISPLAY 0.574468 (-6450 4875);
PAINT GREEN (-6450 4875);
DISPLAY INVISIBLE (-6450 4875);
FORCEPROP 1 LAST HDL_TAP TRUE
J 0
(-6125 4800);
DISPLAY 0.574468 (-6125 4800);
PAINT GREEN (-6125 4800);
DISPLAY INVISIBLE (-6125 4800);
FORCEPROP 1 LAST PATH I346
J 0
(-6452 4925);
DISPLAY 0.872340 (-6452 4925);
PAINT GREEN (-6452 4925);
DISPLAY INVISIBLE (-6452 4925);
FORCEADD TAP..6
(-6450 5025);
FORCEPROP 3 LASTPIN (-6400 5025) SIG_NAME P5E_CPU0_P2_RX_DN<8>
J 0
(-6390 5035);
DISPLAY 0.659574 (-6390 5035);
PAINT MONO (-6390 5035);
DISPLAY INVISIBLE (-6390 5035);
FORCEPROP 1 LASTPIN (-6400 5025) BN 8
J 0
(-6452 5033);
DISPLAY 0.489362 (-6452 5033);
PAINT MONO (-6452 5033);
FORCEPROP 2 LAST CDS_LIB standard
J 0
(-6450 5025);
DISPLAY INVISIBLE (-6450 5025);
FORCEPROP 1 LAST BODY_TYPE PLUMBING
J 0
(-6450 4975);
DISPLAY 0.574468 (-6450 4975);
PAINT GREEN (-6450 4975);
DISPLAY INVISIBLE (-6450 4975);
FORCEPROP 1 LAST HDL_TAP TRUE
J 0
(-6125 4900);
DISPLAY 0.574468 (-6125 4900);
PAINT GREEN (-6125 4900);
DISPLAY INVISIBLE (-6125 4900);
FORCEPROP 1 LAST PATH I347
J 0
(-6452 5025);
DISPLAY 0.872340 (-6452 5025);
PAINT GREEN (-6452 5025);
DISPLAY INVISIBLE (-6452 5025);
FORCEADD TAP..6
(-6450 4825);
FORCEPROP 3 LASTPIN (-6400 4825) SIG_NAME P5E_CPU0_P2_RX_DN<10>
J 0
(-6390 4835);
DISPLAY 0.659574 (-6390 4835);
PAINT MONO (-6390 4835);
DISPLAY INVISIBLE (-6390 4835);
FORCEPROP 1 LASTPIN (-6400 4825) BN 10
J 0
(-6452 4833);
DISPLAY 0.489362 (-6452 4833);
PAINT MONO (-6452 4833);
FORCEPROP 2 LAST CDS_LIB standard
J 0
(-6450 4825);
DISPLAY INVISIBLE (-6450 4825);
FORCEPROP 1 LAST BODY_TYPE PLUMBING
J 0
(-6450 4775);
DISPLAY 0.574468 (-6450 4775);
PAINT GREEN (-6450 4775);
DISPLAY INVISIBLE (-6450 4775);
FORCEPROP 1 LAST HDL_TAP TRUE
J 0
(-6125 4700);
DISPLAY 0.574468 (-6125 4700);
PAINT GREEN (-6125 4700);
DISPLAY INVISIBLE (-6125 4700);
FORCEPROP 1 LAST PATH I348
J 0
(-6452 4825);
DISPLAY 0.872340 (-6452 4825);
PAINT GREEN (-6452 4825);
DISPLAY INVISIBLE (-6452 4825);
FORCEADD TAP..6
(-6450 4725);
FORCEPROP 3 LASTPIN (-6400 4725) SIG_NAME P5E_CPU0_P2_RX_DN<11>
J 0
(-6390 4735);
DISPLAY 0.659574 (-6390 4735);
PAINT MONO (-6390 4735);
DISPLAY INVISIBLE (-6390 4735);
FORCEPROP 1 LASTPIN (-6400 4725) BN 11
J 0
(-6452 4733);
DISPLAY 0.489362 (-6452 4733);
PAINT MONO (-6452 4733);
FORCEPROP 2 LAST CDS_LIB standard
J 0
(-6450 4725);
DISPLAY INVISIBLE (-6450 4725);
FORCEPROP 1 LAST BODY_TYPE PLUMBING
J 0
(-6450 4675);
DISPLAY 0.574468 (-6450 4675);
PAINT GREEN (-6450 4675);
DISPLAY INVISIBLE (-6450 4675);
FORCEPROP 1 LAST HDL_TAP TRUE
J 0
(-6125 4600);
DISPLAY 0.574468 (-6125 4600);
PAINT GREEN (-6125 4600);
DISPLAY INVISIBLE (-6125 4600);
FORCEPROP 1 LAST PATH I349
J 0
(-6452 4725);
DISPLAY 0.872340 (-6452 4725);
PAINT GREEN (-6452 4725);
DISPLAY INVISIBLE (-6452 4725);
FORCEADD TAP..6
(-6300 4575);
FORCEPROP 3 LASTPIN (-6250 4575) SIG_NAME P5E_CPU0_P2_RX_DP<13>
J 0
(-6240 4585);
DISPLAY 0.659574 (-6240 4585);
PAINT MONO (-6240 4585);
DISPLAY INVISIBLE (-6240 4585);
FORCEPROP 1 LASTPIN (-6250 4575) BN 13
J 0
(-6302 4583);
DISPLAY 0.489362 (-6302 4583);
PAINT MONO (-6302 4583);
FORCEPROP 2 LAST CDS_LIB standard
J 0
(-6300 4575);
DISPLAY INVISIBLE (-6300 4575);
FORCEPROP 1 LAST BODY_TYPE PLUMBING
J 0
(-6300 4525);
DISPLAY 0.574468 (-6300 4525);
PAINT GREEN (-6300 4525);
DISPLAY INVISIBLE (-6300 4525);
FORCEPROP 1 LAST HDL_TAP TRUE
J 0
(-5975 4450);
DISPLAY 0.574468 (-5975 4450);
PAINT GREEN (-5975 4450);
DISPLAY INVISIBLE (-5975 4450);
FORCEPROP 1 LAST PATH I350
J 0
(-6302 4575);
DISPLAY 0.872340 (-6302 4575);
PAINT GREEN (-6302 4575);
DISPLAY INVISIBLE (-6302 4575);
FORCEADD TAP..6
(-6300 4475);
FORCEPROP 3 LASTPIN (-6250 4475) SIG_NAME P5E_CPU0_P2_RX_DP<14>
J 0
(-6240 4485);
DISPLAY 0.659574 (-6240 4485);
PAINT MONO (-6240 4485);
DISPLAY INVISIBLE (-6240 4485);
FORCEPROP 1 LASTPIN (-6250 4475) BN 14
J 0
(-6302 4483);
DISPLAY 0.489362 (-6302 4483);
PAINT MONO (-6302 4483);
FORCEPROP 2 LAST CDS_LIB standard
J 0
(-6300 4475);
DISPLAY INVISIBLE (-6300 4475);
FORCEPROP 1 LAST BODY_TYPE PLUMBING
J 0
(-6300 4425);
DISPLAY 0.574468 (-6300 4425);
PAINT GREEN (-6300 4425);
DISPLAY INVISIBLE (-6300 4425);
FORCEPROP 1 LAST HDL_TAP TRUE
J 0
(-5975 4350);
DISPLAY 0.574468 (-5975 4350);
PAINT GREEN (-5975 4350);
DISPLAY INVISIBLE (-5975 4350);
FORCEPROP 1 LAST PATH I351
J 0
(-6302 4475);
DISPLAY 0.872340 (-6302 4475);
PAINT GREEN (-6302 4475);
DISPLAY INVISIBLE (-6302 4475);
FORCEADD TAP..6
(-6300 4375);
FORCEPROP 3 LASTPIN (-6250 4375) SIG_NAME P5E_CPU0_P2_RX_DP<15>
J 0
(-6240 4385);
DISPLAY 0.659574 (-6240 4385);
PAINT MONO (-6240 4385);
DISPLAY INVISIBLE (-6240 4385);
FORCEPROP 1 LASTPIN (-6250 4375) BN 15
J 0
(-6302 4383);
DISPLAY 0.489362 (-6302 4383);
PAINT MONO (-6302 4383);
FORCEPROP 2 LAST CDS_LIB standard
J 0
(-6300 4375);
DISPLAY INVISIBLE (-6300 4375);
FORCEPROP 1 LAST BODY_TYPE PLUMBING
J 0
(-6300 4325);
DISPLAY 0.574468 (-6300 4325);
PAINT GREEN (-6300 4325);
DISPLAY INVISIBLE (-6300 4325);
FORCEPROP 1 LAST HDL_TAP TRUE
J 0
(-5975 4250);
DISPLAY 0.574468 (-5975 4250);
PAINT GREEN (-5975 4250);
DISPLAY INVISIBLE (-5975 4250);
FORCEPROP 1 LAST PATH I352
J 0
(-6302 4375);
DISPLAY 0.872340 (-6302 4375);
PAINT GREEN (-6302 4375);
DISPLAY INVISIBLE (-6302 4375);
FORCEADD TAP..6
(-6450 4625);
FORCEPROP 3 LASTPIN (-6400 4625) SIG_NAME P5E_CPU0_P2_RX_DN<12>
J 0
(-6390 4635);
DISPLAY 0.659574 (-6390 4635);
PAINT MONO (-6390 4635);
DISPLAY INVISIBLE (-6390 4635);
FORCEPROP 1 LASTPIN (-6400 4625) BN 12
J 0
(-6452 4633);
DISPLAY 0.489362 (-6452 4633);
PAINT MONO (-6452 4633);
FORCEPROP 2 LAST CDS_LIB standard
J 0
(-6450 4625);
DISPLAY INVISIBLE (-6450 4625);
FORCEPROP 1 LAST BODY_TYPE PLUMBING
J 0
(-6450 4575);
DISPLAY 0.574468 (-6450 4575);
PAINT GREEN (-6450 4575);
DISPLAY INVISIBLE (-6450 4575);
FORCEPROP 1 LAST HDL_TAP TRUE
J 0
(-6125 4500);
DISPLAY 0.574468 (-6125 4500);
PAINT GREEN (-6125 4500);
DISPLAY INVISIBLE (-6125 4500);
FORCEPROP 1 LAST PATH I353
J 0
(-6452 4625);
DISPLAY 0.872340 (-6452 4625);
PAINT GREEN (-6452 4625);
DISPLAY INVISIBLE (-6452 4625);
FORCEADD TAP..6
(-6450 4425);
FORCEPROP 3 LASTPIN (-6400 4425) SIG_NAME P5E_CPU0_P2_RX_DN<14>
J 0
(-6390 4435);
DISPLAY 0.659574 (-6390 4435);
PAINT MONO (-6390 4435);
DISPLAY INVISIBLE (-6390 4435);
FORCEPROP 1 LASTPIN (-6400 4425) BN 14
J 0
(-6452 4433);
DISPLAY 0.489362 (-6452 4433);
PAINT MONO (-6452 4433);
FORCEPROP 2 LAST CDS_LIB standard
J 0
(-6450 4425);
DISPLAY INVISIBLE (-6450 4425);
FORCEPROP 1 LAST BODY_TYPE PLUMBING
J 0
(-6450 4375);
DISPLAY 0.574468 (-6450 4375);
PAINT GREEN (-6450 4375);
DISPLAY INVISIBLE (-6450 4375);
FORCEPROP 1 LAST HDL_TAP TRUE
J 0
(-6125 4300);
DISPLAY 0.574468 (-6125 4300);
PAINT GREEN (-6125 4300);
DISPLAY INVISIBLE (-6125 4300);
FORCEPROP 1 LAST PATH I354
J 0
(-6452 4425);
DISPLAY 0.872340 (-6452 4425);
PAINT GREEN (-6452 4425);
DISPLAY INVISIBLE (-6452 4425);
FORCEADD TAP..6
(-6450 4525);
FORCEPROP 3 LASTPIN (-6400 4525) SIG_NAME P5E_CPU0_P2_RX_DN<13>
J 0
(-6390 4535);
DISPLAY 0.659574 (-6390 4535);
PAINT MONO (-6390 4535);
DISPLAY INVISIBLE (-6390 4535);
FORCEPROP 1 LASTPIN (-6400 4525) BN 13
J 0
(-6452 4533);
DISPLAY 0.489362 (-6452 4533);
PAINT MONO (-6452 4533);
FORCEPROP 2 LAST CDS_LIB standard
J 0
(-6450 4525);
DISPLAY INVISIBLE (-6450 4525);
FORCEPROP 1 LAST BODY_TYPE PLUMBING
J 0
(-6450 4475);
DISPLAY 0.574468 (-6450 4475);
PAINT GREEN (-6450 4475);
DISPLAY INVISIBLE (-6450 4475);
FORCEPROP 1 LAST HDL_TAP TRUE
J 0
(-6125 4400);
DISPLAY 0.574468 (-6125 4400);
PAINT GREEN (-6125 4400);
DISPLAY INVISIBLE (-6125 4400);
FORCEPROP 1 LAST PATH I355
J 0
(-6452 4525);
DISPLAY 0.872340 (-6452 4525);
PAINT GREEN (-6452 4525);
DISPLAY INVISIBLE (-6452 4525);
FORCEADD TAP..6
(-6450 4325);
FORCEPROP 3 LASTPIN (-6400 4325) SIG_NAME P5E_CPU0_P2_RX_DN<15>
J 0
(-6390 4335);
DISPLAY 0.659574 (-6390 4335);
PAINT MONO (-6390 4335);
DISPLAY INVISIBLE (-6390 4335);
FORCEPROP 1 LASTPIN (-6400 4325) BN 15
J 0
(-6452 4333);
DISPLAY 0.489362 (-6452 4333);
PAINT MONO (-6452 4333);
FORCEPROP 2 LAST CDS_LIB standard
J 0
(-6450 4325);
DISPLAY INVISIBLE (-6450 4325);
FORCEPROP 1 LAST BODY_TYPE PLUMBING
J 0
(-6450 4275);
DISPLAY 0.574468 (-6450 4275);
PAINT GREEN (-6450 4275);
DISPLAY INVISIBLE (-6450 4275);
FORCEPROP 1 LAST HDL_TAP TRUE
J 0
(-6125 4200);
DISPLAY 0.574468 (-6125 4200);
PAINT GREEN (-6125 4200);
DISPLAY INVISIBLE (-6125 4200);
FORCEPROP 1 LAST PATH I356
J 0
(-6452 4325);
DISPLAY 0.872340 (-6452 4325);
PAINT GREEN (-6452 4325);
DISPLAY INVISIBLE (-6452 4325);
FORCEADD OFFPAGE..1
(-7475 6100);
FORCEPROP 2 LAST $XR0 114 
J 0
(-7757 6100);
DISPLAY 0.638298 (-7757 6100);
PAINT MONO (-7757 6100);
FORCEPROP 2 LAST PATH I357
J 0
(-7425 6175);
DISPLAY 1.021277 (-7425 6175);
DISPLAY INVISIBLE (-7425 6175);
FORCEPROP 1 LAST COMMENT_BODY TRUE
J 0
(-7350 6000);
DISPLAY 0.872340 (-7350 6000);
PAINT GREEN (-7350 6000);
DISPLAY INVISIBLE (-7350 6000);
FORCEPROP 1 LAST OFFPAGE TRUE
J 0
(-7150 5975);
DISPLAY 0.872340 (-7150 5975);
PAINT GREEN (-7150 5975);
DISPLAY INVISIBLE (-7150 5975);
FORCEPROP 2 LAST CDS_LIB standard
J 0
(-7475 6100);
DISPLAY INVISIBLE (-7475 6100);
FORCEADD OFFPAGE..1
(-7475 6050);
FORCEPROP 2 LAST $XR0 114 
J 0
(-7757 6050);
DISPLAY 0.638298 (-7757 6050);
PAINT MONO (-7757 6050);
FORCEPROP 2 LAST PATH I358
J 0
(-7425 6125);
DISPLAY 1.021277 (-7425 6125);
DISPLAY INVISIBLE (-7425 6125);
FORCEPROP 1 LAST COMMENT_BODY TRUE
J 0
(-7350 5950);
DISPLAY 0.872340 (-7350 5950);
PAINT GREEN (-7350 5950);
DISPLAY INVISIBLE (-7350 5950);
FORCEPROP 1 LAST OFFPAGE TRUE
J 0
(-7150 5925);
DISPLAY 0.872340 (-7150 5925);
PAINT GREEN (-7150 5925);
DISPLAY INVISIBLE (-7150 5925);
FORCEPROP 2 LAST CDS_LIB standard
J 0
(-7475 6050);
DISPLAY INVISIBLE (-7475 6050);
FORCEADD TAP..6
R 2
(-3850 2250);
FORCEPROP 3 LASTPIN (-3900 2250) SIG_NAME P4E_CPU0_P3_TX_DN<8>
J 0
(-3890 2260);
DISPLAY 0.659574 (-3890 2260);
PAINT MONO (-3890 2260);
DISPLAY INVISIBLE (-3890 2260);
FORCEPROP 1 LASTPIN (-3900 2250) BN 8
J 2
(-3848 2258);
DISPLAY 0.489362 (-3848 2258);
PAINT MONO (-3848 2258);
FORCEPROP 2 LAST CDS_LIB standard
J 0
(-3850 2250);
DISPLAY INVISIBLE (-3850 2250);
FORCEPROP 2 LAST BOM_COST IO_SLOT
J 0
(-4350 2350);
DISPLAY 0.829787 (-4350 2350);
DISPLAY INVISIBLE (-4350 2350);
FORCEPROP 1 LAST BODY_TYPE PLUMBING
J 2
(-3850 2200);
DISPLAY 0.702128 (-3850 2200);
PAINT GREEN (-3850 2200);
DISPLAY INVISIBLE (-3850 2200);
FORCEPROP 1 LAST HDL_TAP TRUE
J 2
(-4175 2125);
DISPLAY 0.702128 (-4175 2125);
PAINT GREEN (-4175 2125);
DISPLAY INVISIBLE (-4175 2125);
FORCEPROP 1 LAST PATH I382
J 2
(-3848 2250);
DISPLAY 0.872340 (-3848 2250);
PAINT GREEN (-3848 2250);
DISPLAY INVISIBLE (-3848 2250);
FORCEPROP 2 LAST ROOM RISER1
J 0
(-4350 2300);
DISPLAY 0.829787 (-4350 2300);
PAINT RED (-4350 2300);
DISPLAY INVISIBLE (-4350 2300);
FORCEADD TAP..6
R 2
(-3850 2150);
FORCEPROP 3 LASTPIN (-3900 2150) SIG_NAME P4E_CPU0_P3_TX_DN<9>
J 0
(-3890 2160);
DISPLAY 0.659574 (-3890 2160);
PAINT MONO (-3890 2160);
DISPLAY INVISIBLE (-3890 2160);
FORCEPROP 1 LASTPIN (-3900 2150) BN 9
J 2
(-3848 2158);
DISPLAY 0.489362 (-3848 2158);
PAINT MONO (-3848 2158);
FORCEPROP 2 LAST CDS_LIB standard
J 0
(-3850 2150);
DISPLAY INVISIBLE (-3850 2150);
FORCEPROP 2 LAST BOM_COST IO_SLOT
J 0
(-4350 2250);
DISPLAY 0.829787 (-4350 2250);
DISPLAY INVISIBLE (-4350 2250);
FORCEPROP 1 LAST BODY_TYPE PLUMBING
J 2
(-3850 2100);
DISPLAY 0.702128 (-3850 2100);
PAINT GREEN (-3850 2100);
DISPLAY INVISIBLE (-3850 2100);
FORCEPROP 1 LAST HDL_TAP TRUE
J 2
(-4175 2025);
DISPLAY 0.702128 (-4175 2025);
PAINT GREEN (-4175 2025);
DISPLAY INVISIBLE (-4175 2025);
FORCEPROP 1 LAST PATH I383
J 2
(-3848 2150);
DISPLAY 0.872340 (-3848 2150);
PAINT GREEN (-3848 2150);
DISPLAY INVISIBLE (-3848 2150);
FORCEPROP 2 LAST ROOM RISER1
J 0
(-4350 2200);
DISPLAY 0.829787 (-4350 2200);
PAINT RED (-4350 2200);
DISPLAY INVISIBLE (-4350 2200);
FORCEADD TAP..6
R 2
(-3850 1950);
FORCEPROP 3 LASTPIN (-3900 1950) SIG_NAME P4E_CPU0_P3_TX_DN<11>
J 0
(-3890 1960);
DISPLAY 0.659574 (-3890 1960);
PAINT MONO (-3890 1960);
DISPLAY INVISIBLE (-3890 1960);
FORCEPROP 1 LASTPIN (-3900 1950) BN 11
J 2
(-3848 1958);
DISPLAY 0.489362 (-3848 1958);
PAINT MONO (-3848 1958);
FORCEPROP 2 LAST CDS_LIB standard
J 0
(-3850 1950);
DISPLAY INVISIBLE (-3850 1950);
FORCEPROP 2 LAST BOM_COST IO_SLOT
J 0
(-4350 2050);
DISPLAY 0.829787 (-4350 2050);
DISPLAY INVISIBLE (-4350 2050);
FORCEPROP 1 LAST BODY_TYPE PLUMBING
J 2
(-3850 1900);
DISPLAY 0.702128 (-3850 1900);
PAINT GREEN (-3850 1900);
DISPLAY INVISIBLE (-3850 1900);
FORCEPROP 1 LAST HDL_TAP TRUE
J 2
(-4175 1825);
DISPLAY 0.702128 (-4175 1825);
PAINT GREEN (-4175 1825);
DISPLAY INVISIBLE (-4175 1825);
FORCEPROP 1 LAST PATH I387
J 2
(-3848 1950);
DISPLAY 0.872340 (-3848 1950);
PAINT GREEN (-3848 1950);
DISPLAY INVISIBLE (-3848 1950);
FORCEPROP 2 LAST ROOM RISER1
J 0
(-4350 2000);
DISPLAY 0.829787 (-4350 2000);
PAINT RED (-4350 2000);
DISPLAY INVISIBLE (-4350 2000);
FORCEADD TAP..6
R 2
(-3850 2050);
FORCEPROP 3 LASTPIN (-3900 2050) SIG_NAME P4E_CPU0_P3_TX_DN<10>
J 0
(-3890 2060);
DISPLAY 0.659574 (-3890 2060);
PAINT MONO (-3890 2060);
DISPLAY INVISIBLE (-3890 2060);
FORCEPROP 1 LASTPIN (-3900 2050) BN 10
J 2
(-3848 2058);
DISPLAY 0.489362 (-3848 2058);
PAINT MONO (-3848 2058);
FORCEPROP 2 LAST CDS_LIB standard
J 0
(-3850 2050);
DISPLAY INVISIBLE (-3850 2050);
FORCEPROP 2 LAST BOM_COST IO_SLOT
J 0
(-4350 2150);
DISPLAY 0.829787 (-4350 2150);
DISPLAY INVISIBLE (-4350 2150);
FORCEPROP 1 LAST BODY_TYPE PLUMBING
J 2
(-3850 2000);
DISPLAY 0.702128 (-3850 2000);
PAINT GREEN (-3850 2000);
DISPLAY INVISIBLE (-3850 2000);
FORCEPROP 1 LAST HDL_TAP TRUE
J 2
(-4175 1925);
DISPLAY 0.702128 (-4175 1925);
PAINT GREEN (-4175 1925);
DISPLAY INVISIBLE (-4175 1925);
FORCEPROP 1 LAST PATH I388
J 2
(-3848 2050);
DISPLAY 0.872340 (-3848 2050);
PAINT GREEN (-3848 2050);
DISPLAY INVISIBLE (-3848 2050);
FORCEPROP 2 LAST ROOM RISER1
J 0
(-4350 2100);
DISPLAY 0.829787 (-4350 2100);
PAINT RED (-4350 2100);
DISPLAY INVISIBLE (-4350 2100);
FORCEADD TAP..6
(-6275 2150);
FORCEPROP 3 LASTPIN (-6225 2150) SIG_NAME P4E_CPU0_P3_RX_DP<9>
J 0
(-6215 2160);
DISPLAY 0.659574 (-6215 2160);
PAINT MONO (-6215 2160);
DISPLAY INVISIBLE (-6215 2160);
FORCEPROP 1 LASTPIN (-6225 2150) BN 9
J 0
(-6277 2158);
DISPLAY 0.489362 (-6277 2158);
PAINT MONO (-6277 2158);
FORCEPROP 2 LAST CDS_LIB standard
J 0
(-6275 2150);
DISPLAY INVISIBLE (-6275 2150);
FORCEPROP 1 LAST BODY_TYPE PLUMBING
J 0
(-6275 2100);
DISPLAY 0.574468 (-6275 2100);
PAINT GREEN (-6275 2100);
DISPLAY INVISIBLE (-6275 2100);
FORCEPROP 1 LAST HDL_TAP TRUE
J 0
(-5950 2025);
DISPLAY 0.574468 (-5950 2025);
PAINT GREEN (-5950 2025);
DISPLAY INVISIBLE (-5950 2025);
FORCEPROP 1 LAST PATH I389
J 0
(-6277 2150);
DISPLAY 0.872340 (-6277 2150);
PAINT GREEN (-6277 2150);
DISPLAY INVISIBLE (-6277 2150);
FORCEADD TAP..6
(-6275 2250);
FORCEPROP 3 LASTPIN (-6225 2250) SIG_NAME P4E_CPU0_P3_RX_DP<8>
J 0
(-6215 2260);
DISPLAY 0.659574 (-6215 2260);
PAINT MONO (-6215 2260);
DISPLAY INVISIBLE (-6215 2260);
FORCEPROP 1 LASTPIN (-6225 2250) BN 8
J 0
(-6277 2258);
DISPLAY 0.489362 (-6277 2258);
PAINT MONO (-6277 2258);
FORCEPROP 2 LAST CDS_LIB standard
J 0
(-6275 2250);
DISPLAY INVISIBLE (-6275 2250);
FORCEPROP 1 LAST BODY_TYPE PLUMBING
J 0
(-6275 2200);
DISPLAY 0.574468 (-6275 2200);
PAINT GREEN (-6275 2200);
DISPLAY INVISIBLE (-6275 2200);
FORCEPROP 1 LAST HDL_TAP TRUE
J 0
(-5950 2125);
DISPLAY 0.574468 (-5950 2125);
PAINT GREEN (-5950 2125);
DISPLAY INVISIBLE (-5950 2125);
FORCEPROP 1 LAST PATH I390
J 0
(-6277 2250);
DISPLAY 0.872340 (-6277 2250);
PAINT GREEN (-6277 2250);
DISPLAY INVISIBLE (-6277 2250);
FORCEADD TAP..6
(-6275 2050);
FORCEPROP 3 LASTPIN (-6225 2050) SIG_NAME P4E_CPU0_P3_RX_DP<10>
J 0
(-6215 2060);
DISPLAY 0.659574 (-6215 2060);
PAINT MONO (-6215 2060);
DISPLAY INVISIBLE (-6215 2060);
FORCEPROP 1 LASTPIN (-6225 2050) BN 10
J 0
(-6277 2058);
DISPLAY 0.489362 (-6277 2058);
PAINT MONO (-6277 2058);
FORCEPROP 2 LAST CDS_LIB standard
J 0
(-6275 2050);
DISPLAY INVISIBLE (-6275 2050);
FORCEPROP 1 LAST BODY_TYPE PLUMBING
J 0
(-6275 2000);
DISPLAY 0.574468 (-6275 2000);
PAINT GREEN (-6275 2000);
DISPLAY INVISIBLE (-6275 2000);
FORCEPROP 1 LAST HDL_TAP TRUE
J 0
(-5950 1925);
DISPLAY 0.574468 (-5950 1925);
PAINT GREEN (-5950 1925);
DISPLAY INVISIBLE (-5950 1925);
FORCEPROP 1 LAST PATH I392
J 0
(-6277 2050);
DISPLAY 0.872340 (-6277 2050);
PAINT GREEN (-6277 2050);
DISPLAY INVISIBLE (-6277 2050);
FORCEADD TAP..6
(-6275 1950);
FORCEPROP 3 LASTPIN (-6225 1950) SIG_NAME P4E_CPU0_P3_RX_DP<11>
J 0
(-6215 1960);
DISPLAY 0.659574 (-6215 1960);
PAINT MONO (-6215 1960);
DISPLAY INVISIBLE (-6215 1960);
FORCEPROP 1 LASTPIN (-6225 1950) BN 11
J 0
(-6277 1958);
DISPLAY 0.489362 (-6277 1958);
PAINT MONO (-6277 1958);
FORCEPROP 2 LAST CDS_LIB standard
J 0
(-6275 1950);
DISPLAY INVISIBLE (-6275 1950);
FORCEPROP 1 LAST BODY_TYPE PLUMBING
J 0
(-6275 1900);
DISPLAY 0.574468 (-6275 1900);
PAINT GREEN (-6275 1900);
DISPLAY INVISIBLE (-6275 1900);
FORCEPROP 1 LAST HDL_TAP TRUE
J 0
(-5950 1825);
DISPLAY 0.574468 (-5950 1825);
PAINT GREEN (-5950 1825);
DISPLAY INVISIBLE (-5950 1825);
FORCEPROP 1 LAST PATH I393
J 0
(-6277 1950);
DISPLAY 0.872340 (-6277 1950);
PAINT GREEN (-6277 1950);
DISPLAY INVISIBLE (-6277 1950);
FORCEADD OFFPAGE..4
R 2
(-7400 2275);
FORCEPROP 2 LAST $XR0 128 
J 0
(-7652 2275);
DISPLAY 0.638298 (-7652 2275);
PAINT MONO (-7652 2275);
FORCEPROP 1 LAST COMMENT_BODY TRUE
J 2
(-7375 2175);
DISPLAY 0.872340 (-7375 2175);
PAINT GREEN (-7375 2175);
DISPLAY INVISIBLE (-7375 2175);
FORCEPROP 1 LAST OFFPAGE TRUE
J 2
(-7725 2150);
DISPLAY 0.872340 (-7725 2150);
PAINT GREEN (-7725 2150);
DISPLAY INVISIBLE (-7725 2150);
FORCEPROP 2 LAST CDS_LIB standard
J 0
(-7400 2275);
DISPLAY INVISIBLE (-7400 2275);
FORCEPROP 2 LAST PATH I398
J 0
(-7675 2325);
DISPLAY 1.021277 (-7675 2325);
DISPLAY INVISIBLE (-7675 2325);
FORCEADD TAP..6
(-6425 2200);
FORCEPROP 3 LASTPIN (-6375 2200) SIG_NAME P4E_CPU0_P3_RX_DN<8>
J 0
(-6365 2210);
DISPLAY 0.659574 (-6365 2210);
PAINT MONO (-6365 2210);
DISPLAY INVISIBLE (-6365 2210);
FORCEPROP 1 LASTPIN (-6375 2200) BN 8
J 0
(-6427 2208);
DISPLAY 0.489362 (-6427 2208);
PAINT MONO (-6427 2208);
FORCEPROP 2 LAST CDS_LIB standard
J 0
(-6425 2200);
DISPLAY INVISIBLE (-6425 2200);
FORCEPROP 1 LAST BODY_TYPE PLUMBING
J 0
(-6425 2150);
DISPLAY 0.574468 (-6425 2150);
PAINT GREEN (-6425 2150);
DISPLAY INVISIBLE (-6425 2150);
FORCEPROP 1 LAST HDL_TAP TRUE
J 0
(-6100 2075);
DISPLAY 0.574468 (-6100 2075);
PAINT GREEN (-6100 2075);
DISPLAY INVISIBLE (-6100 2075);
FORCEPROP 1 LAST PATH I399
J 0
(-6427 2200);
DISPLAY 0.872340 (-6427 2200);
PAINT GREEN (-6427 2200);
DISPLAY INVISIBLE (-6427 2200);
FORCEADD TAP..6
(-6425 2100);
FORCEPROP 3 LASTPIN (-6375 2100) SIG_NAME P4E_CPU0_P3_RX_DN<9>
J 0
(-6365 2110);
DISPLAY 0.659574 (-6365 2110);
PAINT MONO (-6365 2110);
DISPLAY INVISIBLE (-6365 2110);
FORCEPROP 1 LASTPIN (-6375 2100) BN 9
J 0
(-6427 2108);
DISPLAY 0.489362 (-6427 2108);
PAINT MONO (-6427 2108);
FORCEPROP 2 LAST CDS_LIB standard
J 0
(-6425 2100);
DISPLAY INVISIBLE (-6425 2100);
FORCEPROP 1 LAST BODY_TYPE PLUMBING
J 0
(-6425 2050);
DISPLAY 0.574468 (-6425 2050);
PAINT GREEN (-6425 2050);
DISPLAY INVISIBLE (-6425 2050);
FORCEPROP 1 LAST HDL_TAP TRUE
J 0
(-6100 1975);
DISPLAY 0.574468 (-6100 1975);
PAINT GREEN (-6100 1975);
DISPLAY INVISIBLE (-6100 1975);
FORCEPROP 1 LAST PATH I400
J 0
(-6427 2100);
DISPLAY 0.872340 (-6427 2100);
PAINT GREEN (-6427 2100);
DISPLAY INVISIBLE (-6427 2100);
FORCEADD TAP..6
(-6425 2000);
FORCEPROP 3 LASTPIN (-6375 2000) SIG_NAME P4E_CPU0_P3_RX_DN<10>
J 0
(-6365 2010);
DISPLAY 0.659574 (-6365 2010);
PAINT MONO (-6365 2010);
DISPLAY INVISIBLE (-6365 2010);
FORCEPROP 1 LASTPIN (-6375 2000) BN 10
J 0
(-6427 2008);
DISPLAY 0.489362 (-6427 2008);
PAINT MONO (-6427 2008);
FORCEPROP 2 LAST CDS_LIB standard
J 0
(-6425 2000);
DISPLAY INVISIBLE (-6425 2000);
FORCEPROP 1 LAST BODY_TYPE PLUMBING
J 0
(-6425 1950);
DISPLAY 0.574468 (-6425 1950);
PAINT GREEN (-6425 1950);
DISPLAY INVISIBLE (-6425 1950);
FORCEPROP 1 LAST HDL_TAP TRUE
J 0
(-6100 1875);
DISPLAY 0.574468 (-6100 1875);
PAINT GREEN (-6100 1875);
DISPLAY INVISIBLE (-6100 1875);
FORCEPROP 1 LAST PATH I401
J 0
(-6427 2000);
DISPLAY 0.872340 (-6427 2000);
PAINT GREEN (-6427 2000);
DISPLAY INVISIBLE (-6427 2000);
FORCEADD TAP..6
(-6425 1900);
FORCEPROP 3 LASTPIN (-6375 1900) SIG_NAME P4E_CPU0_P3_RX_DN<11>
J 0
(-6365 1910);
DISPLAY 0.659574 (-6365 1910);
PAINT MONO (-6365 1910);
DISPLAY INVISIBLE (-6365 1910);
FORCEPROP 1 LASTPIN (-6375 1900) BN 11
J 0
(-6427 1908);
DISPLAY 0.489362 (-6427 1908);
PAINT MONO (-6427 1908);
FORCEPROP 2 LAST CDS_LIB standard
J 0
(-6425 1900);
DISPLAY INVISIBLE (-6425 1900);
FORCEPROP 1 LAST BODY_TYPE PLUMBING
J 0
(-6425 1850);
DISPLAY 0.574468 (-6425 1850);
PAINT GREEN (-6425 1850);
DISPLAY INVISIBLE (-6425 1850);
FORCEPROP 1 LAST HDL_TAP TRUE
J 0
(-6100 1775);
DISPLAY 0.574468 (-6100 1775);
PAINT GREEN (-6100 1775);
DISPLAY INVISIBLE (-6100 1775);
FORCEPROP 1 LAST PATH I402
J 0
(-6427 1900);
DISPLAY 0.872340 (-6427 1900);
PAINT GREEN (-6427 1900);
DISPLAY INVISIBLE (-6427 1900);
FORCEADD OFFPAGE..4
R 2
(-7400 2225);
FORCEPROP 2 LAST $XR0 128 
J 0
(-7652 2225);
DISPLAY 0.638298 (-7652 2225);
PAINT MONO (-7652 2225);
FORCEPROP 2 LAST PATH I403
J 0
(-7675 2275);
DISPLAY 1.021277 (-7675 2275);
DISPLAY INVISIBLE (-7675 2275);
FORCEPROP 2 LAST CDS_LIB standard
J 0
(-7400 2225);
DISPLAY INVISIBLE (-7400 2225);
FORCEPROP 1 LAST OFFPAGE TRUE
J 2
(-7725 2100);
DISPLAY 0.872340 (-7725 2100);
PAINT GREEN (-7725 2100);
DISPLAY INVISIBLE (-7725 2100);
FORCEPROP 1 LAST COMMENT_BODY TRUE
J 2
(-7375 2125);
DISPLAY 0.872340 (-7375 2125);
PAINT GREEN (-7375 2125);
DISPLAY INVISIBLE (-7375 2125);
FORCEADD TAP..6
R 2
(-3700 1900);
FORCEPROP 3 LASTPIN (-3750 1900) SIG_NAME P4E_CPU0_P3_TX_DP<11>
J 0
(-3740 1910);
DISPLAY 0.659574 (-3740 1910);
PAINT MONO (-3740 1910);
DISPLAY INVISIBLE (-3740 1910);
FORCEPROP 1 LASTPIN (-3750 1900) BN 11
J 2
(-3698 1908);
DISPLAY 0.489362 (-3698 1908);
PAINT MONO (-3698 1908);
FORCEPROP 2 LAST CDS_LIB standard
J 0
(-3700 1900);
DISPLAY INVISIBLE (-3700 1900);
FORCEPROP 2 LAST BOM_COST IO_SLOT
J 0
(-4200 2000);
DISPLAY 0.829787 (-4200 2000);
DISPLAY INVISIBLE (-4200 2000);
FORCEPROP 1 LAST BODY_TYPE PLUMBING
J 2
(-3700 1850);
DISPLAY 0.702128 (-3700 1850);
PAINT GREEN (-3700 1850);
DISPLAY INVISIBLE (-3700 1850);
FORCEPROP 1 LAST HDL_TAP TRUE
J 2
(-4025 1775);
DISPLAY 0.702128 (-4025 1775);
PAINT GREEN (-4025 1775);
DISPLAY INVISIBLE (-4025 1775);
FORCEPROP 1 LAST PATH I404
J 2
(-3698 1900);
DISPLAY 0.872340 (-3698 1900);
PAINT GREEN (-3698 1900);
DISPLAY INVISIBLE (-3698 1900);
FORCEPROP 2 LAST ROOM RISER1
J 0
(-4200 1950);
DISPLAY 0.829787 (-4200 1950);
PAINT RED (-4200 1950);
DISPLAY INVISIBLE (-4200 1950);
FORCEADD TAP..6
R 2
(-3700 2200);
FORCEPROP 3 LASTPIN (-3750 2200) SIG_NAME P4E_CPU0_P3_TX_DP<8>
J 0
(-3740 2210);
DISPLAY 0.659574 (-3740 2210);
PAINT MONO (-3740 2210);
DISPLAY INVISIBLE (-3740 2210);
FORCEPROP 1 LASTPIN (-3750 2200) BN 8
J 2
(-3698 2208);
DISPLAY 0.489362 (-3698 2208);
PAINT MONO (-3698 2208);
FORCEPROP 2 LAST CDS_LIB standard
J 0
(-3700 2200);
DISPLAY INVISIBLE (-3700 2200);
FORCEPROP 2 LAST BOM_COST IO_SLOT
J 0
(-4200 2300);
DISPLAY 0.829787 (-4200 2300);
DISPLAY INVISIBLE (-4200 2300);
FORCEPROP 1 LAST BODY_TYPE PLUMBING
J 2
(-3700 2150);
DISPLAY 0.702128 (-3700 2150);
PAINT GREEN (-3700 2150);
DISPLAY INVISIBLE (-3700 2150);
FORCEPROP 1 LAST HDL_TAP TRUE
J 2
(-4025 2075);
DISPLAY 0.702128 (-4025 2075);
PAINT GREEN (-4025 2075);
DISPLAY INVISIBLE (-4025 2075);
FORCEPROP 1 LAST PATH I406
J 2
(-3698 2200);
DISPLAY 0.872340 (-3698 2200);
PAINT GREEN (-3698 2200);
DISPLAY INVISIBLE (-3698 2200);
FORCEPROP 2 LAST ROOM RISER1
J 0
(-4200 2250);
DISPLAY 0.829787 (-4200 2250);
PAINT RED (-4200 2250);
DISPLAY INVISIBLE (-4200 2250);
FORCEADD TAP..6
R 2
(-3700 2100);
FORCEPROP 3 LASTPIN (-3750 2100) SIG_NAME P4E_CPU0_P3_TX_DP<9>
J 0
(-3740 2110);
DISPLAY 0.659574 (-3740 2110);
PAINT MONO (-3740 2110);
DISPLAY INVISIBLE (-3740 2110);
FORCEPROP 1 LASTPIN (-3750 2100) BN 9
J 2
(-3698 2108);
DISPLAY 0.489362 (-3698 2108);
PAINT MONO (-3698 2108);
FORCEPROP 2 LAST CDS_LIB standard
J 0
(-3700 2100);
DISPLAY INVISIBLE (-3700 2100);
FORCEPROP 2 LAST BOM_COST IO_SLOT
J 0
(-4200 2200);
DISPLAY 0.829787 (-4200 2200);
DISPLAY INVISIBLE (-4200 2200);
FORCEPROP 1 LAST BODY_TYPE PLUMBING
J 2
(-3700 2050);
DISPLAY 0.702128 (-3700 2050);
PAINT GREEN (-3700 2050);
DISPLAY INVISIBLE (-3700 2050);
FORCEPROP 1 LAST HDL_TAP TRUE
J 2
(-4025 1975);
DISPLAY 0.702128 (-4025 1975);
PAINT GREEN (-4025 1975);
DISPLAY INVISIBLE (-4025 1975);
FORCEPROP 1 LAST PATH I407
J 2
(-3698 2100);
DISPLAY 0.872340 (-3698 2100);
PAINT GREEN (-3698 2100);
DISPLAY INVISIBLE (-3698 2100);
FORCEPROP 2 LAST ROOM RISER1
J 0
(-4200 2150);
DISPLAY 0.829787 (-4200 2150);
PAINT RED (-4200 2150);
DISPLAY INVISIBLE (-4200 2150);
FORCEADD TAP..6
R 2
(-3700 2000);
FORCEPROP 3 LASTPIN (-3750 2000) SIG_NAME P4E_CPU0_P3_TX_DP<10>
J 0
(-3740 2010);
DISPLAY 0.659574 (-3740 2010);
PAINT MONO (-3740 2010);
DISPLAY INVISIBLE (-3740 2010);
FORCEPROP 1 LASTPIN (-3750 2000) BN 10
J 2
(-3698 2008);
DISPLAY 0.489362 (-3698 2008);
PAINT MONO (-3698 2008);
FORCEPROP 2 LAST CDS_LIB standard
J 0
(-3700 2000);
DISPLAY INVISIBLE (-3700 2000);
FORCEPROP 2 LAST BOM_COST IO_SLOT
J 0
(-4200 2100);
DISPLAY 0.829787 (-4200 2100);
DISPLAY INVISIBLE (-4200 2100);
FORCEPROP 1 LAST BODY_TYPE PLUMBING
J 2
(-3700 1950);
DISPLAY 0.702128 (-3700 1950);
PAINT GREEN (-3700 1950);
DISPLAY INVISIBLE (-3700 1950);
FORCEPROP 1 LAST HDL_TAP TRUE
J 2
(-4025 1875);
DISPLAY 0.702128 (-4025 1875);
PAINT GREEN (-4025 1875);
DISPLAY INVISIBLE (-4025 1875);
FORCEPROP 1 LAST PATH I408
J 2
(-3698 2000);
DISPLAY 0.872340 (-3698 2000);
PAINT GREEN (-3698 2000);
DISPLAY INVISIBLE (-3698 2000);
FORCEPROP 2 LAST ROOM RISER1
J 0
(-4200 2050);
DISPLAY 0.829787 (-4200 2050);
PAINT RED (-4200 2050);
DISPLAY INVISIBLE (-4200 2050);
FORCEADD OFFPAGE..2
(-2700 2275);
FORCEPROP 2 LAST $XR0 64 
J 0
(-2511 2275);
DISPLAY 0.638298 (-2511 2275);
PAINT MONO (-2511 2275);
FORCEPROP 2 LAST PATH I410
J 0
(-2500 2325);
DISPLAY 1.021277 (-2500 2325);
DISPLAY INVISIBLE (-2500 2325);
FORCEPROP 2 LAST CDS_LIB standard
J 0
(-2700 2275);
DISPLAY INVISIBLE (-2700 2275);
FORCEPROP 1 LAST OFFPAGE TRUE
J 0
(-2375 2150);
DISPLAY 0.872340 (-2375 2150);
PAINT GREEN (-2375 2150);
DISPLAY INVISIBLE (-2375 2150);
FORCEPROP 1 LAST COMMENT_BODY TRUE
J 0
(-2745 2180);
DISPLAY 0.872340 (-2745 2180);
PAINT GREEN (-2745 2180);
DISPLAY INVISIBLE (-2745 2180);
FORCEADD OFFPAGE..2
(-2700 2225);
FORCEPROP 2 LAST $XR0 64 
J 0
(-2511 2225);
DISPLAY 0.638298 (-2511 2225);
PAINT MONO (-2511 2225);
FORCEPROP 2 LAST PATH I411
J 0
(-2500 2275);
DISPLAY 1.021277 (-2500 2275);
DISPLAY INVISIBLE (-2500 2275);
FORCEPROP 1 LAST COMMENT_BODY TRUE
J 0
(-2745 2130);
DISPLAY 0.872340 (-2745 2130);
PAINT GREEN (-2745 2130);
DISPLAY INVISIBLE (-2745 2130);
FORCEPROP 1 LAST OFFPAGE TRUE
J 0
(-2375 2100);
DISPLAY 0.872340 (-2375 2100);
PAINT GREEN (-2375 2100);
DISPLAY INVISIBLE (-2375 2100);
FORCEPROP 2 LAST CDS_LIB standard
J 0
(-2700 2225);
DISPLAY INVISIBLE (-2700 2225);
FORCEADD QUANTA_TITLE_BLOCK_C..1
(-100 100);
FORCEPROP 0 LAST CDS_CON_LAST_MODIFIED Fri Mar 11 14:52:20 2022
J 0
(-1985 115);
DISPLAY INVISIBLE (-1985 115);
FORCEPROP 1 LAST CUSTOM_TXT_CDS <CON_LAST_MODIFIED>
J 0
(-1985 115);
DISPLAY 0.978723 (-1985 115);
FORCEPROP 2 LAST CUSTOM_TXT_CDS <XR_PAGE_TITLE>
J 0
(-7990 5350);
DISPLAY 0.638298 (-7990 5350);
PAINT PINK (-7990 5350);
DISPLAY INVISIBLE (-7990 5350);
FORCEPROP 1 LAST CUSTOM_TXT_CDS <NAME_2>
J 0
(-3275 150);
FORCEPROP 1 LAST CUSTOM_TXT_CDS <NAME_1>
J 0
(-3275 275);
FORCEPROP 1 LAST CUSTOM_TXT_CDS <Q_NUMBER>
J 0
(-1503 203);
DISPLAY 1.212766 (-1503 203);
FORCEPROP 1 LAST CUSTOM_TXT_CDS <Q_PROJ>
J 0
(-2482 202);
DISPLAY 1.212766 (-2482 202);
FORCEPROP 1 LAST CUSTOM_TXT_CDS <Q_REV>
J 0
(-284 203);
DISPLAY 1.212766 (-284 203);
FORCEPROP 1 LAST CUSTOM_TXT_CDS <CON_PAGE_NUM> OF <CON_TOTAL_PAGES>
J 0
(-546 118);
DISPLAY 0.978723 (-546 118);
FORCEPROP 1 LAST Q_DEPT BU9
J 1
(-3863 149);
DISPLAY 1.957447 (-3863 149);
PAINT GREEN (-3863 149);
FORCEPROP 1 LAST Q_TITLE CPU0 PCIE P2/P3
J 0
(-9425 150);
DISPLAY 2.446809 (-9425 150);
PAINT GREEN (-9425 150);
FORCEPROP 2 LAST CDS_LIB pure_quanta
J 0
(-100 100);
DISPLAY INVISIBLE (-100 100);
FORCEPROP 1 LAST CDS_LMAN_SYM_OUTLINE -9475,6775,100,-125
J 0
(-100 100);
DISPLAY 0.468085 (-100 100);
PAINT GREEN (-100 100);
DISPLAY INVISIBLE (-100 100);
FORCEPROP 2 LAST PAGE_BORDER TRUE
J 0
(-7990 5350);
DISPLAY 0.638298 (-7990 5350);
PAINT PINK (-7990 5350);
DISPLAY INVISIBLE (-7990 5350);
FORCEPROP 1 LAST COMMENT_BODY TRUE
J 0
(-88 87);
DISPLAY 0.978723 (-88 87);
PAINT GREEN (-88 87);
DISPLAY INVISIBLE (-88 87);
FORCEPROP 2 LAST CDS_XR_PAGE_TITLE CR-25 : @T6G_MB_LIB.T6G(SCH_1):PAGE25
J 0
(-7990 5350);
DISPLAY 0.638298 (-7990 5350);
PAINT PINK (-7990 5350);
DISPLAY INVISIBLE (-7990 5350);
WIRE 17 -1 (-3800 2675)(-3800 2575);
WIRE 17 -1 (-3800 2675)(-2775 2675);
FORCEPROP 2 LAST SIG_NAME P5E_CPU0_P3_TX_DP<7:4>
J 0
(-3475 2685);
DISPLAY 0.489362 (-3475 2685);
WIRE 17 -1 (-3650 2625)(-3650 2525);
WIRE 17 -1 (-3650 2625)(-2775 2625);
FORCEPROP 2 LAST SIG_NAME P5E_CPU0_P3_TX_DN<7:4>
J 0
(-3475 2635);
DISPLAY 0.489362 (-3475 2635);
WIRE 17 -1 (-3800 2575)(-3800 2475);
WIRE 17 -1 (-3800 2475)(-3800 2375);
WIRE 17 -1 (-3650 2525)(-3650 2425);
WIRE 17 -1 (-3650 2425)(-3650 2325);
WIRE 17 -1 (-3800 2275)(-3800 2175);
WIRE 17 -1 (-3800 2275)(-2750 2275);
FORCEPROP 2 LAST SIG_NAME P4E_CPU0_P3_TX_DN<11:8>
J 0
(-3475 2285);
DISPLAY 0.489362 (-3475 2285);
WIRE 17 -1 (-3650 2225)(-3650 2125);
WIRE 17 -1 (-3650 2225)(-2750 2225);
FORCEPROP 2 LAST SIG_NAME P4E_CPU0_P3_TX_DP<11:8>
J 0
(-3475 2235);
DISPLAY 0.489362 (-3475 2235);
WIRE 17 -1 (-3800 2175)(-3800 2075);
WIRE 17 -1 (-3800 2075)(-3800 1975);
WIRE 17 -1 (-3650 2125)(-3650 2025);
WIRE 17 -1 (-3650 2025)(-3650 1925);
WIRE 17 -1 (-3800 5100)(-3800 5000);
WIRE 17 -1 (-3800 5200)(-3800 5100);
WIRE 17 -1 (-3800 5000)(-3800 4900);
WIRE 17 -1 (-3800 4900)(-3800 4800);
WIRE 17 -1 (-3800 5300)(-3800 5200);
WIRE 17 -1 (-3800 5400)(-3800 5300);
WIRE 17 -1 (-3800 4800)(-3800 4700);
WIRE 17 -1 (-3800 4700)(-3800 4600);
WIRE 17 -1 (-3800 5500)(-3800 5400);
WIRE 17 -1 (-3800 5600)(-3800 5500);
WIRE 17 -1 (-3800 4600)(-3800 4500);
WIRE 17 -1 (-3800 4500)(-3800 4400);
WIRE 17 -1 (-3800 5700)(-3800 5600);
WIRE 17 -1 (-3800 5800)(-3800 5700);
WIRE 17 -1 (-3800 5900)(-3800 5800);
WIRE 17 -1 (-3800 6100)(-3800 5900);
WIRE 17 -1 (-3800 6100)(-2775 6100);
FORCEPROP 2 LAST SIG_NAME P5E_CPU0_P2_TX_DP<15:0>
J 0
(-3510 6110);
DISPLAY 0.489362 (-3510 6110);
WIRE 17 -1 (-3650 5050)(-3650 4950);
WIRE 17 -1 (-3650 5150)(-3650 5050);
WIRE 17 -1 (-3650 4950)(-3650 4850);
WIRE 17 -1 (-3650 4850)(-3650 4750);
WIRE 17 -1 (-3650 5250)(-3650 5150);
WIRE 17 -1 (-3650 5350)(-3650 5250);
WIRE 17 -1 (-3650 4750)(-3650 4650);
WIRE 17 -1 (-3650 4650)(-3650 4550);
WIRE 17 -1 (-3650 5450)(-3650 5350);
WIRE 17 -1 (-3650 5550)(-3650 5450);
WIRE 17 -1 (-3650 4550)(-3650 4450);
WIRE 17 -1 (-3650 4450)(-3650 4350);
WIRE 17 -1 (-3650 5650)(-3650 5550);
WIRE 17 -1 (-3650 5750)(-3650 5650);
WIRE 17 -1 (-3650 5850)(-3650 5750);
WIRE 17 -1 (-3650 6050)(-3650 5850);
WIRE 17 -1 (-3650 6050)(-2775 6050);
FORCEPROP 2 LAST SIG_NAME P5E_CPU0_P2_TX_DN<15:0>
J 0
(-3510 6060);
DISPLAY 0.489362 (-3510 6060);
WIRE 17 -1 (-6350 5100)(-6350 5200);
WIRE 17 -1 (-6350 5000)(-6350 5100);
WIRE 17 -1 (-6350 5200)(-6350 5300);
WIRE 17 -1 (-6350 5300)(-6350 5400);
WIRE 17 -1 (-6350 4900)(-6350 5000);
WIRE 17 -1 (-6350 4800)(-6350 4900);
WIRE 17 -1 (-6350 5400)(-6350 5500);
WIRE 17 -1 (-6350 5500)(-6350 5600);
WIRE 17 -1 (-6350 4700)(-6350 4800);
WIRE 17 -1 (-6350 4600)(-6350 4700);
WIRE 17 -1 (-6350 5600)(-6350 5700);
WIRE 17 -1 (-6350 5700)(-6350 5800);
WIRE 17 -1 (-6350 4500)(-6350 4600);
WIRE 17 -1 (-6350 4400)(-6350 4500);
WIRE 17 -1 (-6350 5800)(-6350 5900);
WIRE 17 -1 (-6350 5900)(-6350 6100);
WIRE 17 -1 (-6350 6100)(-7425 6100);
FORCEPROP 2 LAST SIG_NAME P5E_CPU0_P2_RX_DP<15:0>
J 0
(-7200 6110);
DISPLAY 0.489362 (-7200 6110);
WIRE 17 -1 (-6500 5050)(-6500 5150);
WIRE 17 -1 (-6500 4950)(-6500 5050);
WIRE 17 -1 (-6500 5150)(-6500 5250);
WIRE 17 -1 (-6500 5250)(-6500 5350);
WIRE 17 -1 (-6500 4850)(-6500 4950);
WIRE 17 -1 (-6500 4750)(-6500 4850);
WIRE 17 -1 (-6500 5350)(-6500 5450);
WIRE 17 -1 (-6500 5450)(-6500 5550);
WIRE 17 -1 (-6500 4650)(-6500 4750);
WIRE 17 -1 (-6500 4550)(-6500 4650);
WIRE 17 -1 (-6500 5550)(-6500 5650);
WIRE 17 -1 (-6500 5650)(-6500 5750);
WIRE 17 -1 (-6500 4450)(-6500 4550);
WIRE 17 -1 (-6500 4350)(-6500 4450);
WIRE 17 -1 (-6500 5750)(-6500 5850);
WIRE 17 -1 (-6500 5850)(-6500 6050);
WIRE 17 -1 (-6500 6050)(-7425 6050);
FORCEPROP 2 LAST SIG_NAME P5E_CPU0_P2_RX_DN<15:0>
J 0
(-7200 6060);
DISPLAY 0.489362 (-7200 6060);
WIRE 17 -1 (-6325 2575)(-6325 2675);
WIRE 17 -1 (-6325 2475)(-6325 2575);
WIRE 17 -1 (-6325 2675)(-7325 2675);
FORCEPROP 2 LAST SIG_NAME P5E_CPU0_P3_RX_DP<7:4>
J 0
(-7350 2685);
DISPLAY 0.489362 (-7350 2685);
WIRE 17 -1 (-6475 2525)(-6475 2625);
WIRE 17 -1 (-6475 2425)(-6475 2525);
WIRE 17 -1 (-6475 2625)(-7325 2625);
WIRE 17 -1 (-6325 2375)(-6325 2475);
WIRE 17 -1 (-6475 2325)(-6475 2425);
WIRE 17 -1 (-6325 2275)(-6325 2175);
WIRE 17 -1 (-7350 2275)(-6325 2275);
FORCEPROP 2 LAST SIG_NAME P4E_CPU0_P3_RX_DP<11:8>
J 0
(-7350 2285);
DISPLAY 0.489362 (-7350 2285);
WIRE 17 -1 (-6475 2125)(-6475 2225);
WIRE 17 -1 (-6475 2125)(-6475 2025);
WIRE 17 -1 (-7350 2225)(-6475 2225);
FORCEPROP 2 LAST SIG_NAME P4E_CPU0_P3_RX_DN<11:8>
J 0
(-7350 2235);
DISPLAY 0.489362 (-7350 2235);
WIRE 17 -1 (-6325 2175)(-6325 2075);
WIRE 17 -1 (-6325 2075)(-6325 1975);
WIRE 17 -1 (-6475 2025)(-6475 1925);
WIRE 16 -1 (-5775 1900)(-6375 1900);
WIRE 16 -1 (-5775 1950)(-6225 1950);
WIRE 16 -1 (-5775 2000)(-6375 2000);
WIRE 16 -1 (-5775 2050)(-6225 2050);
WIRE 16 -1 (-5775 2100)(-6375 2100);
WIRE 16 -1 (-5775 2150)(-6225 2150);
WIRE 16 -1 (-5775 2200)(-6375 2200);
WIRE 16 -1 (-5775 2250)(-6225 2250);
WIRE 16 -1 (-6375 2300)(-5775 2300);
WIRE 16 -1 (-6225 2350)(-5775 2350);
WIRE 16 -1 (-6375 2400)(-5775 2400);
WIRE 16 -1 (-6225 2450)(-5775 2450);
WIRE 16 -1 (-6375 2500)(-5775 2500);
WIRE 16 -1 (-6225 2550)(-5775 2550);
WIRE 16 -1 (-6375 2600)(-5775 2600);
WIRE 16 -1 (-6225 2650)(-5775 2650);
WIRE 16 -1 (-7325 3000)(-5775 3000);
FORCEPROP 2 LAST SIG_NAME P3E_CPU0_P3_RX_DP<0>
J 0
(-7350 3010);
DISPLAY 0.489362 (-7350 3010);
WIRE 16 -1 (-7325 3050)(-5775 3050);
FORCEPROP 2 LAST SIG_NAME P3E_CPU0_P3_RX_DN<0>
J 0
(-7350 3060);
DISPLAY 0.489362 (-7350 3060);
WIRE 16 -1 (-6400 5125)(-5775 5125);
WIRE 16 -1 (-6400 5225)(-5775 5225);
WIRE 16 -1 (-6400 5325)(-5775 5325);
WIRE 16 -1 (-6250 5175)(-5775 5175);
WIRE 16 -1 (-6400 5425)(-5775 5425);
WIRE 16 -1 (-6250 5275)(-5775 5275);
WIRE 16 -1 (-6400 5525)(-5775 5525);
WIRE 16 -1 (-6250 5375)(-5775 5375);
WIRE 16 -1 (-6400 5625)(-5775 5625);
WIRE 16 -1 (-6250 5475)(-5775 5475);
WIRE 16 -1 (-6400 5725)(-5775 5725);
WIRE 16 -1 (-6250 5575)(-5775 5575);
WIRE 16 -1 (-6400 5825)(-5775 5825);
WIRE 16 -1 (-6250 5675)(-5775 5675);
WIRE 16 -1 (-6250 5775)(-5775 5775);
WIRE 16 -1 (-6250 5875)(-5775 5875);
WIRE 16 -1 (-6400 4325)(-5775 4325);
WIRE 16 -1 (-6250 4375)(-5775 4375);
WIRE 16 -1 (-6400 4425)(-5775 4425);
WIRE 16 -1 (-6250 4475)(-5775 4475);
WIRE 16 -1 (-6400 4525)(-5775 4525);
WIRE 16 -1 (-6250 4575)(-5775 4575);
WIRE 16 -1 (-6400 4625)(-5775 4625);
WIRE 16 -1 (-6250 4675)(-5775 4675);
WIRE 16 -1 (-6400 4725)(-5775 4725);
WIRE 16 -1 (-6250 4775)(-5775 4775);
WIRE 16 -1 (-6400 4825)(-5775 4825);
WIRE 16 -1 (-6250 4875)(-5775 4875);
WIRE 16 -1 (-6400 4925)(-5775 4925);
WIRE 16 -1 (-6250 4975)(-5775 4975);
WIRE 16 -1 (-6400 5025)(-5775 5025);
WIRE 16 -1 (-6250 5075)(-5775 5075);
WIRE 16 -1 (-4275 5125)(-3750 5125);
WIRE 16 -1 (-4275 5225)(-3750 5225);
WIRE 16 -1 (-4275 5325)(-3750 5325);
WIRE 16 -1 (-4275 5175)(-3900 5175);
WIRE 16 -1 (-4275 5425)(-3750 5425);
WIRE 16 -1 (-4275 5275)(-3900 5275);
WIRE 16 -1 (-4275 5525)(-3750 5525);
WIRE 16 -1 (-4275 5375)(-3900 5375);
WIRE 16 -1 (-4275 5625)(-3750 5625);
WIRE 16 -1 (-4275 5475)(-3900 5475);
WIRE 16 -1 (-4275 5725)(-3750 5725);
WIRE 16 -1 (-4275 5575)(-3900 5575);
WIRE 16 -1 (-4275 5825)(-3750 5825);
WIRE 16 -1 (-4275 5675)(-3900 5675);
WIRE 16 -1 (-4275 5775)(-3900 5775);
WIRE 16 -1 (-4275 5875)(-3900 5875);
WIRE 16 -1 (-4275 4325)(-3750 4325);
WIRE 16 -1 (-4275 4375)(-3900 4375);
WIRE 16 -1 (-4275 4425)(-3750 4425);
WIRE 16 -1 (-4275 4475)(-3900 4475);
WIRE 16 -1 (-4275 4525)(-3750 4525);
WIRE 16 -1 (-4275 4575)(-3900 4575);
WIRE 16 -1 (-4275 4625)(-3750 4625);
WIRE 16 -1 (-4275 4675)(-3900 4675);
WIRE 16 -1 (-4275 4725)(-3750 4725);
WIRE 16 -1 (-4275 4775)(-3900 4775);
WIRE 16 -1 (-4275 4825)(-3750 4825);
WIRE 16 -1 (-4275 4875)(-3900 4875);
WIRE 16 -1 (-4275 4925)(-3750 4925);
WIRE 16 -1 (-4275 4975)(-3900 4975);
WIRE 16 -1 (-4275 5025)(-3750 5025);
WIRE 16 -1 (-4275 5075)(-3900 5075);
WIRE 16 -1 (-3750 1900)(-4275 1900);
WIRE 16 -1 (-3900 1950)(-4275 1950);
WIRE 16 -1 (-3750 2000)(-4275 2000);
WIRE 16 -1 (-3900 2050)(-4275 2050);
WIRE 16 -1 (-3750 2100)(-4275 2100);
WIRE 16 -1 (-3900 2150)(-4275 2150);
WIRE 16 -1 (-3750 2200)(-4275 2200);
WIRE 16 -1 (-3900 2250)(-4275 2250);
WIRE 16 -1 (-4275 2300)(-3750 2300);
WIRE 16 -1 (-3900 2350)(-4275 2350);
WIRE 16 -1 (-4275 2400)(-3750 2400);
WIRE 16 -1 (-4275 2450)(-3900 2450);
WIRE 16 -1 (-4275 2500)(-3750 2500);
WIRE 16 -1 (-4275 2550)(-3900 2550);
WIRE 16 -1 (-4275 2600)(-3750 2600);
WIRE 16 -1 (-4275 2650)(-3900 2650);
WIRE 16 -1 (-4275 3050)(-2775 3050);
FORCEPROP 2 LAST SIG_NAME P3E_CPU0_P3_TX_DP<0>
J 0
(-3475 3060);
DISPLAY 0.489362 (-3475 3060);
WIRE 16 -1 (-4275 3000)(-2775 3000);
FORCEPROP 2 LAST SIG_NAME P3E_CPU0_P3_TX_DN<0>
J 0
(-3475 3010);
DISPLAY 0.489362 (-3475 3010);
FORCENOTE
CPU0 P3[11:8] TO M.2#1
(-3125 850) 0;
DISPLAY LEFT (-3125 850);
DISPLAY 2.000000 (-3125 850);
FORCENOTE
CPU0 P3[7:4] TO SCM(RFU)
(-3125 1200) 0;
DISPLAY LEFT (-3125 1200);
DISPLAY 2.000000 (-3125 1200);
FORCENOTE
CPU0 P3[0] TO SCM
(-3125 1450) 0;
DISPLAY LEFT (-3125 1450);
DISPLAY 2.000000 (-3125 1450);
FORCENOTE
CPU0 P2[15:0] TO SLOT#1
(-3025 5075) 0;
DISPLAY LEFT (-3025 5075);
DISPLAY 2.000000 (-3025 5075);
FORCENOTE
(TX PN SWAP)
(-3150 700) 0;
DISPLAY LEFT (-3150 700);
DISPLAY 2.000000 (-3150 700);
QUIT
